G04 ================== begin FILE IDENTIFICATION RECORD ==================*
G04 Layout Name:  14545-sa.brd*
G04 Film Name:    DIF_REF_BOTTOM*
G04 File Format:  Gerber RS274X*
G04 File Origin:  Cadence Allegro 16.5-S056*
G04 Origin Date:  Fri Aug 01 17:59:07 2014*
G04 *
G04 Layer:  BOARD GEOMETRY/OUTLINE*
G04 Layer:  BOARD GEOMETRY/DIF_REF_BOTTOM*
G04 Layer:  BOARD GEOMETRY/PANEL_OUTLINE*
G04 *
G04 Offset:    (0.00 0.00)*
G04 Mirror:    No*
G04 Mode:      Positive*
G04 Rotation:  0*
G04 FullContactRelief:  No*
G04 UndefLineWidth:     6.00*
G04 ================== end FILE IDENTIFICATION RECORD ====================*
%FSLAX35Y35*MOIN*%
%IR0*IPPOS*OFA0.00000B0.00000*MIA0B0*SFA1.00000B1.00000*%
%ADD10C,.006*%
%ADD11C,.00375*%
G75*
%LPD*%
G75*
G54D10*
G01X-78741Y15000D02*
G03X-63741Y0I15000J0D01*
G01X-78741Y15000D02*
Y120047D01*
G01X-63741Y135047D02*
G03X-78741Y120047I0J-15000D01*
G01Y298866D02*
G03X-63741Y283866I15000J0D01*
G01X-78741Y319646D02*
Y298866D01*
G01X-63741Y334646D02*
G03X-78741Y319646I0J-15000D01*
G01Y908315D02*
G03X-63741Y893315I15000J0D01*
G01X-78741Y908315D02*
Y1104299D01*
G01X-63741Y1119299D02*
G03X-78741Y1104299I0J-15000D01*
G01Y1283118D02*
G03X-63741Y1268118I15000J0D01*
G01X-78741Y1304285D02*
Y1283118D01*
G01X-63741Y1319285D02*
G03X-78741Y1304285I0J-15000D01*
G01Y1892953D02*
G03X-63741Y1877953I15000J0D01*
G01X-78741Y1892953D02*
Y1977126D01*
G01X-63741Y1992126D02*
G03X-78741Y1977126I0J-15000D01*
G01X19882Y1197835D02*
X1969D01*
X0Y1195866D01*
Y832480D01*
X1969Y830512D01*
X19882D01*
G02Y823031I0J-3740D01*
G01X1969D01*
X0Y821063D01*
Y423031D01*
X1969Y421063D01*
X19882D01*
G02Y413583I0J-3740D01*
G01X1969D01*
X0Y411614D01*
Y223031D01*
X1969Y221063D01*
X19882D01*
G02Y213583I0J-3740D01*
G01X1969D01*
X0Y211614D01*
Y3937D01*
G03X3937Y0I3937J0D01*
G01X1029528D01*
G03X1033465Y3937I0J3937D01*
G01Y1424882D01*
X1029528Y1428819D01*
X1024213D01*
G02X1019291Y1433740I-1J4921D01*
G01Y1607933D01*
X1015354Y1611870D01*
X989744D01*
G02Y1616083I0J2107D01*
G01X1015354D01*
X1019291Y1620020D01*
Y1676496D01*
G02X1024213Y1681417I4921J0D01*
G01X1029528D01*
X1033465Y1685354D01*
Y1988189D01*
G03X1029528Y1992126I-3937J0D01*
G01X3937D01*
G03X0Y1988189I0J-3937D01*
G01Y1816732D01*
X1969Y1814764D01*
X19882D01*
G02Y1807283I0J-3740D01*
G01X1969D01*
X0Y1805315D01*
Y1407283D01*
X1969Y1405315D01*
X19882D01*
G02Y1397835I0J-3740D01*
G01X1969D01*
X0Y1395866D01*
Y1207283D01*
X1969Y1205315D01*
X19882D01*
G02Y1197835I0J-3740D01*
G01Y1197834D02*
X1969D01*
X0Y1195865D01*
Y832479D01*
X1969Y830511D01*
X19882D01*
G02Y823030I0J-3741D01*
G01X1969D01*
X0Y821062D01*
Y423030D01*
X1969Y421062D01*
X19882D01*
G02Y413582I0J-3740D01*
G01X1969D01*
X0Y411613D01*
Y223030D01*
X1969Y221062D01*
X19882D01*
G02Y213582I0J-3740D01*
G01X1969D01*
X0Y211613D01*
Y3936D01*
G03X3937Y-1I3937J0D01*
G01X1029528D01*
G03X1033465Y3936I0J3937D01*
G01Y1424881D01*
X1029528Y1428818D01*
X1024213D01*
G02X1019291Y1433739I-1J4921D01*
G01Y1607932D01*
X1015354Y1611869D01*
X989744D01*
G02Y1616082I0J2107D01*
G01X1015354D01*
X1019291Y1620019D01*
Y1676495D01*
G02X1024213Y1681416I4921J0D01*
G01X1029528D01*
X1033465Y1685353D01*
Y1988188D01*
G03X1029528Y1992125I-3937J0D01*
G01X3937D01*
G03X0Y1988188I0J-3937D01*
G01Y1816731D01*
X1969Y1814763D01*
X19882D01*
G02Y1807282I0J-3741D01*
G01X1969D01*
X0Y1805314D01*
Y1407282D01*
X1969Y1405314D01*
X19882D01*
G02Y1397834I0J-3740D01*
G01X1969D01*
X0Y1395865D01*
Y1207282D01*
X1969Y1205314D01*
X19882D01*
G02Y1197834I0J-3740D01*
G01X-7875Y0D02*
X-63741D01*
G01X-7875Y41772D02*
Y104969D01*
G01Y17252D02*
Y0D01*
G01Y41772D02*
G03X-1I3937J-1D01*
G01Y17213D02*
G03X-7875I-3937J0D01*
G01Y41772D02*
G03X-1I3937J-1D01*
G01Y17213D02*
G03X-7875I-3937J0D01*
G01Y129516D02*
Y135047D01*
G01D02*
X-63741D01*
G01X-7875Y129516D02*
G03X-1I3937J0D01*
G01Y104958D02*
G03X-7875I-3937J0D01*
G01Y283866D02*
Y300383D01*
G01X-19814Y283866D02*
X-63741D01*
G01X-7875D02*
X-19814D01*
G01X-1Y300383D02*
G03X-7875I-3937J0D01*
G01Y331986D02*
Y324003D01*
G01Y331986D02*
Y334646D01*
G01D02*
X-63741D01*
G01X-7875Y324003D02*
G03X-1I3937J0D01*
G01X-7875Y905988D02*
Y893315D01*
G01D02*
X-63741D01*
G01X-7875Y1069005D02*
Y933234D01*
G01D02*
G03X-1I3937J0D01*
G01Y905988D02*
G03X-7875I-3937J0D01*
G01Y1108863D02*
Y1119299D01*
G01X-19126D02*
X-7875D01*
G01X-15749D02*
X-63741D01*
G01X-7875Y1106300D02*
Y1111425D01*
G01Y1106300D02*
Y1092625D01*
G01D02*
G03X-1I3937J0D01*
G01Y1069005D02*
G03X-7875I-3937J0D01*
G01X-17894Y1268118D02*
X-7875D01*
G01Y1278280D02*
Y1268118D01*
G01Y1280567D02*
Y1275992D01*
G01X-15749Y1268118D02*
X-63741D01*
G01X-7875Y1309889D02*
G03X-1I3937J0D01*
G01Y1280567D02*
G03X-7875I-3937J0D01*
G01Y1309889D02*
G03X-1I3937J0D01*
G01Y1280567D02*
G03X-7875I-3937J0D01*
G01Y1309889D02*
Y1319285D01*
G01D02*
X-63741D01*
G01X-7875Y1889223D02*
Y1877953D01*
G01D02*
X-63741D01*
G01X-7875Y1912843D02*
Y1962926D01*
G01Y1912843D02*
G03X-1I3937J0D01*
G01Y1889223D02*
G03X-7875I-3937J0D01*
G01Y1912843D02*
G03X-1I3937J0D01*
G01Y1889223D02*
G03X-7875I-3937J0D01*
G01X-1Y1962926D02*
G03X-7875I-3937J0D01*
G01X-1D02*
G03X-7875I-3937J0D01*
G01Y1986546D02*
Y1992126D01*
G01D02*
X-63741D01*
G01X-7875Y1986546D02*
G03X-1I3937J0D01*
G01X-7875D02*
G03X-1I3937J0D01*
G01X37330Y-70164D02*
Y-82164D01*
G01X35030Y-70164D02*
X39630D01*
G01X41630Y-82164D02*
Y-70164D01*
G01Y-75964D02*
X42130Y-74964D01*
X42630Y-74364D01*
X43430Y-74164D01*
X44030Y-74364D01*
X44730Y-75164D01*
X45030Y-76364D01*
Y-82164D01*
G01X49330Y-74164D02*
Y-82164D01*
G01Y-70964D02*
X49130Y-70764D01*
Y-70364D01*
X49330Y-70164D01*
X49530Y-70364D01*
Y-70764D01*
X49330Y-70964D01*
G01X53830Y-80764D02*
X54330Y-81564D01*
X55030Y-82164D01*
X55630D01*
X56230Y-81764D01*
X56630Y-81164D01*
X56830Y-80364D01*
X56730Y-79164D01*
X56330Y-78564D01*
X54530Y-77364D01*
X54130Y-75964D01*
X54330Y-74964D01*
X54730Y-74364D01*
X55330Y-74164D01*
X55930Y-74364D01*
X56530Y-74964D01*
G01X65930Y-85164D02*
X66630Y-85964D01*
X67430Y-86164D01*
X68130Y-85964D01*
X68730Y-84964D01*
X69130Y-83564D01*
Y-74164D01*
G01Y-75764D02*
X68730Y-74964D01*
X68130Y-74364D01*
X67430Y-74164D01*
X66630Y-74564D01*
X66130Y-75364D01*
X65730Y-76764D01*
X65530Y-78164D01*
X65630Y-79364D01*
X66030Y-80764D01*
X66630Y-81764D01*
X67430Y-82164D01*
X68030Y-81964D01*
X68730Y-81164D01*
X69130Y-80364D01*
G01X71830Y-76764D02*
X75030D01*
X74730Y-75364D01*
X74230Y-74564D01*
X73530Y-74164D01*
X72830Y-74364D01*
X72230Y-74964D01*
X71830Y-76364D01*
X71630Y-77564D01*
Y-78764D01*
X71830Y-79964D01*
X72330Y-81164D01*
X72930Y-81964D01*
X73630Y-82164D01*
X74330Y-81764D01*
X75030Y-80564D01*
G01X77930Y-82164D02*
Y-74164D01*
G01Y-75764D02*
X78430Y-74964D01*
X78930Y-74364D01*
X79630Y-74164D01*
X80130Y-74364D01*
X80730Y-74964D01*
G01X83530Y-82164D02*
Y-70164D01*
G01Y-76164D02*
X84030Y-74964D01*
X84630Y-74364D01*
X85230Y-74164D01*
X86130Y-74564D01*
X86730Y-75364D01*
X87130Y-76764D01*
Y-78364D01*
X86930Y-79964D01*
X86530Y-81164D01*
X85830Y-81964D01*
X85230Y-82164D01*
X84630Y-81964D01*
X84030Y-81364D01*
X83530Y-80364D01*
G01X89830Y-76764D02*
X93030D01*
X92730Y-75364D01*
X92230Y-74564D01*
X91530Y-74164D01*
X90830Y-74364D01*
X90230Y-74964D01*
X89830Y-76364D01*
X89630Y-77564D01*
Y-78764D01*
X89830Y-79964D01*
X90330Y-81164D01*
X90930Y-81964D01*
X91630Y-82164D01*
X92330Y-81764D01*
X93030Y-80564D01*
G01X95930Y-82164D02*
Y-74164D01*
G01Y-75764D02*
X96430Y-74964D01*
X96930Y-74364D01*
X97630Y-74164D01*
X98130Y-74364D01*
X98730Y-74964D01*
G01X109330Y-74164D02*
Y-82164D01*
G01Y-70964D02*
X109130Y-70764D01*
Y-70364D01*
X109330Y-70164D01*
X109530Y-70364D01*
Y-70764D01*
X109330Y-70964D01*
G01X113830Y-80764D02*
X114330Y-81564D01*
X115030Y-82164D01*
X115630D01*
X116230Y-81764D01*
X116630Y-81164D01*
X116830Y-80364D01*
X116730Y-79164D01*
X116330Y-78564D01*
X114530Y-77364D01*
X114130Y-75964D01*
X114330Y-74964D01*
X114730Y-74364D01*
X115330Y-74164D01*
X115930Y-74364D01*
X116530Y-74964D01*
G01X125730Y-85164D02*
X126430Y-85964D01*
X127030Y-86164D01*
X127830Y-85764D01*
X128430Y-84764D01*
X128730Y-82964D01*
Y-74164D01*
G01Y-70964D02*
X128530Y-70764D01*
Y-70364D01*
X128730Y-70164D01*
X128930Y-70364D01*
Y-70764D01*
X128730Y-70964D01*
G01X131630Y-74164D02*
Y-79764D01*
X132030Y-81164D01*
X132630Y-81964D01*
X133330Y-82164D01*
X134030Y-81964D01*
X134630Y-81164D01*
X135030Y-79764D01*
G01Y-82164D02*
Y-74164D01*
G01X137830Y-80764D02*
X138330Y-81564D01*
X139030Y-82164D01*
X139630D01*
X140230Y-81764D01*
X140630Y-81164D01*
X140830Y-80364D01*
X140730Y-79164D01*
X140330Y-78564D01*
X138530Y-77364D01*
X138130Y-75964D01*
X138330Y-74964D01*
X138730Y-74364D01*
X139330Y-74164D01*
X139930Y-74364D01*
X140530Y-74964D01*
G01X145330Y-70164D02*
Y-82164D01*
G01X143930Y-74164D02*
X146730D01*
G01X156730Y-82164D02*
Y-71964D01*
X156930Y-70964D01*
X157330Y-70364D01*
X157930Y-70164D01*
X158530Y-70564D01*
X158830Y-71564D01*
G01X157630Y-74964D02*
X155630D01*
G01X163330Y-82164D02*
X162730Y-81964D01*
X162130Y-81164D01*
X161730Y-79764D01*
X161530Y-78164D01*
X161730Y-76564D01*
X162130Y-75164D01*
X162730Y-74364D01*
X163330Y-74164D01*
X163930Y-74364D01*
X164530Y-75164D01*
X164930Y-76564D01*
X165030Y-78164D01*
X164930Y-79764D01*
X164530Y-81164D01*
X163930Y-81964D01*
X163330Y-82164D01*
G01X167930D02*
Y-74164D01*
G01Y-75764D02*
X168430Y-74964D01*
X168930Y-74364D01*
X169630Y-74164D01*
X170130Y-74364D01*
X170730Y-74964D01*
G01X179230Y-85764D02*
X179830Y-86164D01*
X180630Y-85764D01*
X181130Y-84964D01*
X181530Y-83964D01*
X182130Y-80764D01*
X183430Y-74164D01*
G01X180230D02*
X182130Y-80764D01*
G01X187330Y-82164D02*
X186730Y-81964D01*
X186130Y-81164D01*
X185730Y-79764D01*
X185530Y-78164D01*
X185730Y-76564D01*
X186130Y-75164D01*
X186730Y-74364D01*
X187330Y-74164D01*
X187930Y-74364D01*
X188530Y-75164D01*
X188930Y-76564D01*
X189030Y-78164D01*
X188930Y-79764D01*
X188530Y-81164D01*
X187930Y-81964D01*
X187330Y-82164D01*
G01X191630Y-74164D02*
Y-79764D01*
X192030Y-81164D01*
X192630Y-81964D01*
X193330Y-82164D01*
X194030Y-81964D01*
X194630Y-81164D01*
X195030Y-79764D01*
G01Y-82164D02*
Y-74164D01*
G01X203930Y-82164D02*
Y-74164D01*
G01Y-75764D02*
X204430Y-74964D01*
X204930Y-74364D01*
X205630Y-74164D01*
X206130Y-74364D01*
X206730Y-74964D01*
G01X209830Y-76764D02*
X213030D01*
X212730Y-75364D01*
X212230Y-74564D01*
X211530Y-74164D01*
X210830Y-74364D01*
X210230Y-74964D01*
X209830Y-76364D01*
X209630Y-77564D01*
Y-78764D01*
X209830Y-79964D01*
X210330Y-81164D01*
X210930Y-81964D01*
X211630Y-82164D01*
X212330Y-81764D01*
X213030Y-80564D01*
G01X216730Y-82164D02*
Y-71964D01*
X216930Y-70964D01*
X217330Y-70364D01*
X217930Y-70164D01*
X218530Y-70564D01*
X218830Y-71564D01*
G01X217630Y-74964D02*
X215630D01*
G01X221830Y-76764D02*
X225030D01*
X224730Y-75364D01*
X224230Y-74564D01*
X223530Y-74164D01*
X222830Y-74364D01*
X222230Y-74964D01*
X221830Y-76364D01*
X221630Y-77564D01*
Y-78764D01*
X221830Y-79964D01*
X222330Y-81164D01*
X222930Y-81964D01*
X223630Y-82164D01*
X224330Y-81764D01*
X225030Y-80564D01*
G01X227930Y-82164D02*
Y-74164D01*
G01Y-75764D02*
X228430Y-74964D01*
X228930Y-74364D01*
X229630Y-74164D01*
X230130Y-74364D01*
X230730Y-74964D01*
G01X233830Y-76764D02*
X237030D01*
X236730Y-75364D01*
X236230Y-74564D01*
X235530Y-74164D01*
X234830Y-74364D01*
X234230Y-74964D01*
X233830Y-76364D01*
X233630Y-77564D01*
Y-78764D01*
X233830Y-79964D01*
X234330Y-81164D01*
X234930Y-81964D01*
X235630Y-82164D01*
X236330Y-81764D01*
X237030Y-80564D01*
G01X239630Y-82164D02*
Y-74164D01*
G01Y-76164D02*
X240030Y-75164D01*
X240630Y-74364D01*
X241430Y-74164D01*
X242130Y-74364D01*
X242730Y-75164D01*
X243030Y-76564D01*
Y-82164D01*
G01X248930Y-75164D02*
X248230Y-74364D01*
X247630Y-74164D01*
X246830Y-74564D01*
X246230Y-75364D01*
X245830Y-76764D01*
X245730Y-78164D01*
X245830Y-79564D01*
X246230Y-80764D01*
X246830Y-81764D01*
X247630Y-82164D01*
X248330Y-81764D01*
X248930Y-80964D01*
G01X251830Y-76764D02*
X255030D01*
X254730Y-75364D01*
X254230Y-74564D01*
X253530Y-74164D01*
X252830Y-74364D01*
X252230Y-74964D01*
X251830Y-76364D01*
X251630Y-77564D01*
Y-78764D01*
X251830Y-79964D01*
X252330Y-81164D01*
X252930Y-81964D01*
X253630Y-82164D01*
X254330Y-81764D01*
X255030Y-80564D01*
G01X265330Y-70164D02*
Y-82164D01*
G01X263930Y-74164D02*
X266730D01*
G01X271330Y-82164D02*
X270730Y-81964D01*
X270130Y-81164D01*
X269730Y-79764D01*
X269530Y-78164D01*
X269730Y-76564D01*
X270130Y-75164D01*
X270730Y-74364D01*
X271330Y-74164D01*
X271930Y-74364D01*
X272530Y-75164D01*
X272930Y-76564D01*
X273030Y-78164D01*
X272930Y-79764D01*
X272530Y-81164D01*
X271930Y-81964D01*
X271330Y-82164D01*
G01X282730D02*
Y-71964D01*
X282930Y-70964D01*
X283330Y-70364D01*
X283930Y-70164D01*
X284530Y-70564D01*
X284830Y-71564D01*
G01X283630Y-74964D02*
X281630D01*
G01X289330Y-74164D02*
Y-82164D01*
G01Y-70964D02*
X289130Y-70764D01*
Y-70364D01*
X289330Y-70164D01*
X289530Y-70364D01*
Y-70764D01*
X289330Y-70964D01*
G01X293630Y-82164D02*
Y-74164D01*
G01Y-76164D02*
X294030Y-75164D01*
X294630Y-74364D01*
X295430Y-74164D01*
X296130Y-74364D01*
X296730Y-75164D01*
X297030Y-76564D01*
Y-82164D01*
G01X303130Y-70164D02*
Y-82164D01*
G01Y-80364D02*
X302730Y-81364D01*
X302130Y-81964D01*
X301430Y-82164D01*
X300630Y-81764D01*
X300030Y-80764D01*
X299630Y-79564D01*
X299530Y-78164D01*
X299630Y-76764D01*
X300030Y-75564D01*
X300630Y-74564D01*
X301430Y-74164D01*
X302130Y-74364D01*
X302630Y-74764D01*
X303130Y-75564D01*
G01X313330Y-70164D02*
Y-82164D01*
G01X311930Y-74164D02*
X314730D01*
G01X317630Y-82164D02*
Y-70164D01*
G01Y-75964D02*
X318130Y-74964D01*
X318630Y-74364D01*
X319430Y-74164D01*
X320030Y-74364D01*
X320730Y-75164D01*
X321030Y-76364D01*
Y-82164D01*
G01X323830Y-76764D02*
X327030D01*
X326730Y-75364D01*
X326230Y-74564D01*
X325530Y-74164D01*
X324830Y-74364D01*
X324230Y-74964D01*
X323830Y-76364D01*
X323630Y-77564D01*
Y-78764D01*
X323830Y-79964D01*
X324330Y-81164D01*
X324930Y-81964D01*
X325630Y-82164D01*
X326330Y-81764D01*
X327030Y-80564D01*
G01X339130Y-70164D02*
Y-82164D01*
G01Y-80364D02*
X338730Y-81364D01*
X338130Y-81964D01*
X337430Y-82164D01*
X336630Y-81764D01*
X336030Y-80764D01*
X335630Y-79564D01*
X335530Y-78164D01*
X335630Y-76764D01*
X336030Y-75564D01*
X336630Y-74564D01*
X337430Y-74164D01*
X338130Y-74364D01*
X338630Y-74764D01*
X339130Y-75564D01*
G01X343330Y-74164D02*
Y-82164D01*
G01Y-70964D02*
X343130Y-70764D01*
Y-70364D01*
X343330Y-70164D01*
X343530Y-70364D01*
Y-70764D01*
X343330Y-70964D01*
G01X348730Y-82164D02*
Y-71964D01*
X348930Y-70964D01*
X349330Y-70364D01*
X349930Y-70164D01*
X350530Y-70564D01*
X350830Y-71564D01*
G01X349630Y-74964D02*
X347630D01*
G01X354730Y-82164D02*
Y-71964D01*
X354930Y-70964D01*
X355330Y-70364D01*
X355930Y-70164D01*
X356530Y-70564D01*
X356830Y-71564D01*
G01X355630Y-74964D02*
X353630D01*
G01X359830Y-76764D02*
X363030D01*
X362730Y-75364D01*
X362230Y-74564D01*
X361530Y-74164D01*
X360830Y-74364D01*
X360230Y-74964D01*
X359830Y-76364D01*
X359630Y-77564D01*
Y-78764D01*
X359830Y-79964D01*
X360330Y-81164D01*
X360930Y-81964D01*
X361630Y-82164D01*
X362330Y-81764D01*
X363030Y-80564D01*
G01X365930Y-82164D02*
Y-74164D01*
G01Y-75764D02*
X366430Y-74964D01*
X366930Y-74364D01*
X367630Y-74164D01*
X368130Y-74364D01*
X368730Y-74964D01*
G01X371830Y-76764D02*
X375030D01*
X374730Y-75364D01*
X374230Y-74564D01*
X373530Y-74164D01*
X372830Y-74364D01*
X372230Y-74964D01*
X371830Y-76364D01*
X371630Y-77564D01*
Y-78764D01*
X371830Y-79964D01*
X372330Y-81164D01*
X372930Y-81964D01*
X373630Y-82164D01*
X374330Y-81764D01*
X375030Y-80564D01*
G01X377630Y-82164D02*
Y-74164D01*
G01Y-76164D02*
X378030Y-75164D01*
X378630Y-74364D01*
X379430Y-74164D01*
X380130Y-74364D01*
X380730Y-75164D01*
X381030Y-76564D01*
Y-82164D01*
G01X385330Y-70164D02*
Y-82164D01*
G01X383930Y-74164D02*
X386730D01*
G01X391330D02*
Y-82164D01*
G01Y-70964D02*
X391130Y-70764D01*
Y-70364D01*
X391330Y-70164D01*
X391530Y-70364D01*
Y-70764D01*
X391330Y-70964D01*
G01X399130Y-82164D02*
Y-74164D01*
G01Y-75564D02*
X398730Y-74764D01*
X398130Y-74364D01*
X397430Y-74164D01*
X396730Y-74564D01*
X396130Y-75364D01*
X395730Y-76564D01*
X395530Y-78164D01*
X395730Y-79764D01*
X396130Y-80964D01*
X396730Y-81764D01*
X397430Y-82164D01*
X398130Y-81964D01*
X398730Y-81364D01*
X399130Y-80564D01*
G01X403330Y-82164D02*
Y-70164D01*
G01X415330D02*
Y-82164D01*
G01X413930Y-74164D02*
X416730D01*
G01X419930Y-82164D02*
Y-74164D01*
G01Y-75764D02*
X420430Y-74964D01*
X420930Y-74364D01*
X421630Y-74164D01*
X422130Y-74364D01*
X422730Y-74964D01*
G01X429130Y-82164D02*
Y-74164D01*
G01Y-75564D02*
X428730Y-74764D01*
X428130Y-74364D01*
X427430Y-74164D01*
X426730Y-74564D01*
X426130Y-75364D01*
X425730Y-76564D01*
X425530Y-78164D01*
X425730Y-79764D01*
X426130Y-80964D01*
X426730Y-81764D01*
X427430Y-82164D01*
X428130Y-81964D01*
X428730Y-81364D01*
X429130Y-80564D01*
G01X434930Y-75164D02*
X434230Y-74364D01*
X433630Y-74164D01*
X432830Y-74564D01*
X432230Y-75364D01*
X431830Y-76764D01*
X431730Y-78164D01*
X431830Y-79564D01*
X432230Y-80764D01*
X432830Y-81764D01*
X433630Y-82164D01*
X434330Y-81764D01*
X434930Y-80964D01*
G01X437830Y-76764D02*
X441030D01*
X440730Y-75364D01*
X440230Y-74564D01*
X439530Y-74164D01*
X438830Y-74364D01*
X438230Y-74964D01*
X437830Y-76364D01*
X437630Y-77564D01*
Y-78764D01*
X437830Y-79964D01*
X438330Y-81164D01*
X438930Y-81964D01*
X439630Y-82164D01*
X440330Y-81764D01*
X441030Y-80564D01*
G01X443830Y-80764D02*
X444330Y-81564D01*
X445030Y-82164D01*
X445630D01*
X446230Y-81764D01*
X446630Y-81164D01*
X446830Y-80364D01*
X446730Y-79164D01*
X446330Y-78564D01*
X444530Y-77364D01*
X444130Y-75964D01*
X444330Y-74964D01*
X444730Y-74364D01*
X445330Y-74164D01*
X445930Y-74364D01*
X446530Y-74964D01*
G01X457330Y-74164D02*
Y-82164D01*
G01Y-70964D02*
X457130Y-70764D01*
Y-70364D01*
X457330Y-70164D01*
X457530Y-70364D01*
Y-70764D01*
X457330Y-70964D01*
G01X461630Y-82164D02*
Y-74164D01*
G01Y-76164D02*
X462030Y-75164D01*
X462630Y-74364D01*
X463430Y-74164D01*
X464130Y-74364D01*
X464730Y-75164D01*
X465030Y-76564D01*
Y-82164D01*
G01X475330D02*
Y-70164D01*
G01X483130Y-82164D02*
Y-74164D01*
G01Y-75564D02*
X482730Y-74764D01*
X482130Y-74364D01*
X481430Y-74164D01*
X480730Y-74564D01*
X480130Y-75364D01*
X479730Y-76564D01*
X479530Y-78164D01*
X479730Y-79764D01*
X480130Y-80964D01*
X480730Y-81764D01*
X481430Y-82164D01*
X482130Y-81964D01*
X482730Y-81364D01*
X483130Y-80564D01*
G01X485230Y-85764D02*
X485830Y-86164D01*
X486630Y-85764D01*
X487130Y-84964D01*
X487530Y-83964D01*
X488130Y-80764D01*
X489430Y-74164D01*
G01X486230D02*
X488130Y-80764D01*
G01X491830Y-76764D02*
X495030D01*
X494730Y-75364D01*
X494230Y-74564D01*
X493530Y-74164D01*
X492830Y-74364D01*
X492230Y-74964D01*
X491830Y-76364D01*
X491630Y-77564D01*
Y-78764D01*
X491830Y-79964D01*
X492330Y-81164D01*
X492930Y-81964D01*
X493630Y-82164D01*
X494330Y-81764D01*
X495030Y-80564D01*
G01X497930Y-82164D02*
Y-74164D01*
G01Y-75764D02*
X498430Y-74964D01*
X498930Y-74364D01*
X499630Y-74164D01*
X500130Y-74364D01*
X500730Y-74964D01*
G01X512130Y-75764D02*
X512530Y-75164D01*
X512830Y-74164D01*
X513030Y-72764D01*
X512830Y-71564D01*
X512430Y-70764D01*
X511730Y-70164D01*
X509030D01*
Y-82164D01*
X512330D01*
X513030Y-81364D01*
X513430Y-80164D01*
X513630Y-78764D01*
X513430Y-77364D01*
X512830Y-76164D01*
X512130Y-75764D01*
X509030D01*
G01X517330Y-82164D02*
X516530Y-81964D01*
X515830Y-81164D01*
X515230Y-79964D01*
X514830Y-78564D01*
X514630Y-76964D01*
Y-75364D01*
X514830Y-73764D01*
X515230Y-72364D01*
X515830Y-71164D01*
X516530Y-70364D01*
X517330Y-70164D01*
X518130Y-70364D01*
X518830Y-71164D01*
X519430Y-72364D01*
X519830Y-73764D01*
X520030Y-75364D01*
Y-76964D01*
X519830Y-78564D01*
X519430Y-79964D01*
X518830Y-81164D01*
X518130Y-81964D01*
X517330Y-82164D01*
G01X523330Y-70164D02*
Y-82164D01*
G01X521030Y-70164D02*
X525630D01*
G01X529330D02*
Y-82164D01*
G01X527030Y-70164D02*
X531630D01*
G01X535330Y-82164D02*
X534530Y-81964D01*
X533830Y-81164D01*
X533230Y-79964D01*
X532830Y-78564D01*
X532630Y-76964D01*
Y-75364D01*
X532830Y-73764D01*
X533230Y-72364D01*
X533830Y-71164D01*
X534530Y-70364D01*
X535330Y-70164D01*
X536130Y-70364D01*
X536830Y-71164D01*
X537430Y-72364D01*
X537830Y-73764D01*
X538030Y-75364D01*
Y-76964D01*
X537830Y-78564D01*
X537430Y-79964D01*
X536830Y-81164D01*
X536130Y-81964D01*
X535330Y-82164D01*
G01X538730D02*
Y-70164D01*
X541330Y-80164D01*
X543930Y-70164D01*
Y-82164D01*
G01X1041337Y24677D02*
Y0D01*
G01Y217343D02*
Y48297D01*
G01Y0D02*
X1097204D01*
G01X1033463Y48297D02*
G03X1041337I3937J0D01*
G01Y24677D02*
G03X1033463I-3937J0D01*
G01Y48297D02*
G03X1041337I3937J0D01*
G01Y24677D02*
G03X1033463I-3937J0D01*
G01X1041337Y217343D02*
G03X1033463I-3937J0D01*
G01X1041337D02*
G03X1033463I-3937J0D01*
G01X1041337Y445039D02*
Y240963D01*
G01X1033463D02*
G03X1041337I3937J0D01*
G01X1033463D02*
G03X1041337I3937J0D01*
G01Y697474D02*
Y468601D01*
G01X1033463Y468659D02*
G03X1041337I3937J0D01*
G01Y445039D02*
G03X1033463I-3937J0D01*
G01Y468659D02*
G03X1041337I3937J0D01*
G01Y445039D02*
G03X1033463I-3937J0D01*
G01X1041337Y996851D02*
Y721093D01*
G01X1033463D02*
G03X1041337I3937J0D01*
G01Y697474D02*
G03X1033463I-3937J-1D01*
G01Y721093D02*
G03X1041337I3937J0D01*
G01Y697474D02*
G03X1033463I-3937J-1D01*
G01X1041337Y1344059D02*
Y1020472D01*
G01X1033463D02*
G03X1041337I3937J0D01*
G01Y996851D02*
G03X1033463I-3937J1D01*
G01Y1020472D02*
G03X1041337I3937J0D01*
G01Y996851D02*
G03X1033463I-3937J1D01*
G01X1041337Y1367679D02*
Y1393701D01*
G01X1033463Y1367679D02*
G03X1041337I3937J0D01*
G01Y1344059D02*
G03X1033463I-3937J0D01*
G01Y1367679D02*
G03X1041337I3937J0D01*
G01Y1344059D02*
G03X1033463I-3937J0D01*
G01X1041337Y1393701D02*
X1097204D01*
G01X1041337Y1733129D02*
Y1716535D01*
G01X1065042D02*
X1041337D01*
G01X1056337D02*
X1097204D01*
G01X1041337Y1739719D02*
Y1731535D01*
G01Y1959242D02*
Y1763311D01*
G01X1033463Y1763339D02*
G03X1041337I3937J0D01*
G01Y1739719D02*
G03X1033463I-3937J0D01*
G01Y1763339D02*
G03X1041337I3937J0D01*
G01Y1739719D02*
G03X1033463I-3937J0D01*
G01X1041337Y1959242D02*
G03X1033463I-3937J0D01*
G01X1041337D02*
G03X1033463I-3937J0D01*
G01X1041337Y1992126D02*
X1097204D01*
G01X1041337Y1982862D02*
Y1992126D01*
G01X1033463Y1982862D02*
G03X1041337I3937J0D01*
G01X1033463D02*
G03X1041337I3937J0D01*
G01X1112204Y648419D02*
Y15000D01*
G01X1097204Y0D02*
G03X1112204Y15000I0J15000D01*
G01Y656293D02*
G03Y648419I0J-3937D01*
G01Y1378701D02*
Y656293D01*
G01Y1378701D02*
G03X1097204Y1393701I-15000J0D01*
G01Y1716535D02*
G03X1112204Y1731535I0J15000D01*
G01Y1977126D02*
Y1731535D01*
G01Y1977126D02*
G03X1097204Y1992126I-15000J0D01*
G54D11*
G01X19151Y379915D02*
X11069D01*
G01X19671Y375999D02*
X11069Y375978D01*
G01Y395663D02*
X19664D01*
G01X11069Y391726D02*
X19494D01*
G01X11069Y450783D02*
X19727D01*
G01X11069Y446846D02*
X11075Y446852D01*
G01D02*
X19827D01*
G01X11069Y435035D02*
X19410D01*
G01X11069Y431098D02*
X19787D01*
G01X19194Y478342D02*
X11069D01*
G01X18735Y466531D02*
X11069D01*
G01X19394Y462594D02*
X11069D01*
G01X19947Y411417D02*
X11075D01*
G01D02*
X11069Y411411D01*
G01X19829Y407474D02*
X11069D01*
G01X18994Y513775D02*
X11069D01*
G01X19959Y509844D02*
X11075D01*
G01D02*
X11069Y509838D01*
G01X19294Y529523D02*
X11069D01*
G01X19553Y525586D02*
X11069D01*
G01X19554Y498027D02*
X11069D01*
G01X19640Y494090D02*
X11069D01*
G01X19394Y482279D02*
X11069D01*
G01X19632Y631885D02*
X11069D01*
G01X19683Y627948D02*
X11069D01*
G01X18472Y643696D02*
X11069D01*
G01X18274Y616137D02*
X11069D01*
G01X18295Y612200D02*
X11069D01*
G01Y584641D02*
X18459D01*
G01X18349Y580704D02*
X11069D01*
G01X19613Y647633D02*
X11069D01*
G01X19862Y663387D02*
X11075D01*
G01D02*
X11069Y663381D01*
G01Y659444D02*
X19162D01*
G01X18347Y679129D02*
X11069D01*
G01Y675192D02*
X18982D01*
G01X18899Y1364167D02*
X11069D01*
G01X19020Y1360230D02*
X11069D01*
G01Y1379915D02*
X11075Y1379921D01*
G01D02*
X19953D01*
G01X11069Y1375978D02*
X18519D01*
G01X19574Y1395663D02*
X11069D01*
G01X20051Y1391732D02*
X11075D01*
G01D02*
X11069Y1391726D01*
G01X18858Y1419287D02*
X11069D01*
G01X19322Y1415350D02*
X11069D01*
G01X18502Y1466531D02*
X11069D01*
G01X18494Y1462594D02*
X11069D01*
G01X19209Y1450783D02*
X11069D01*
G01X19128Y1446846D02*
X11069D01*
G01Y1435035D02*
X18940D01*
G01X19467Y1431098D02*
X11069D01*
G01X19381Y1498027D02*
X11069D01*
G01X19783Y1494096D02*
X11075D01*
G01D02*
X11069Y1494090D01*
G01X19254Y1482279D02*
X11069D01*
G01X19186Y1478342D02*
X11069D01*
G01X19183Y1513775D02*
X11069D01*
G01Y1509838D02*
X19440D01*
G01X19367Y1631885D02*
X11069D01*
G01X18998Y1627948D02*
X11069D01*
G01X18513Y1616137D02*
X11069D01*
G01X18566Y1612200D02*
X11069D01*
G01X17988Y1600389D02*
X11069D01*
G01X18857Y1596452D02*
X11069D01*
G01X18103Y1568893D02*
X11069D01*
G01X18511Y1564956D02*
X11069D01*
G01X18407Y1647633D02*
X11069D01*
G01X18566Y1643696D02*
X11069D01*
G01X18532Y1663381D02*
X11069D01*
G01X19044Y1659444D02*
X11069D01*
G01X98432Y123484D02*
G02X94970Y122050I-3462J3462D01*
G01D02*
X86672D01*
G01D02*
G02X83157Y123402I1J5247D01*
G01D02*
G02X82956Y123593I3630J4022D01*
G01D02*
X63249Y143300D01*
G01D02*
X62925Y143623D01*
G01D02*
X61998Y144550D01*
G01D02*
G02X61299Y146238I1688J1688D01*
G01D02*
Y346253D01*
G01X99352Y122564D02*
G02X94969Y120750I-4381J4383D01*
G01D02*
X86671D01*
G01D02*
G02X82285Y122436I0J6548D01*
G01D02*
G02X82036Y122673I4506J4984D01*
G01D02*
X62703Y142006D01*
G01D02*
X62330Y142380D01*
G01D02*
X62006Y142703D01*
G01D02*
X61078Y143630D01*
G01D02*
G02X59999Y146239I2609J2606D01*
G01D02*
Y346252D01*
G01X86599Y126750D02*
X86671Y126822D01*
G01D02*
G02X87835Y127478I1757J-1757D01*
G01D02*
G02X88146Y127534I595J-2413D01*
G01D02*
G02X88423Y127550I281J-2456D01*
G01D02*
X92015D01*
G01D02*
G03X99499Y130650I0J10584D01*
G01X86899Y130567D02*
G03X86099Y129767I0J-800D01*
G01D02*
G03X87016Y128850I917J0D01*
G01D02*
X92014D01*
G01D02*
G03X98579Y131570I0J9283D01*
G01X101299Y177250D02*
G03X92927Y197462I-28584J0D01*
G01D02*
X66376Y224013D01*
G01D02*
G02X64999Y227335I3322J3323D01*
G01D02*
Y352757D01*
G01X99999Y177250D02*
G03X92007Y196542I-27284J-1D01*
G01D02*
X65456Y223093D01*
G01D02*
G02X63699Y227334I4242J4242D01*
G01D02*
Y352756D01*
G01X68699Y354748D02*
Y292614D01*
G01D02*
G03X70017Y289432I4500J0D01*
G01D02*
X124931Y234518D01*
G01X67399Y354747D02*
Y292613D01*
G01D02*
G03X69098Y288512I5800J0D01*
G01D02*
X124011Y233599D01*
G01X72399Y358665D02*
Y294223D01*
G01D02*
G03X73299Y292050I3073J0D01*
G01D02*
X126249Y239100D01*
G01X71099Y358665D02*
Y294350D01*
G01D02*
G03X72470Y291040I4681J0D01*
G01D02*
X125479Y238031D01*
G01X118194Y266194D02*
X76831Y307557D01*
G01D02*
G02X76099Y309325I1768J1768D01*
G01D02*
Y367876D01*
G01X125998Y256550D02*
X75912Y306636D01*
G01D02*
G02X74799Y309323I2687J2687D01*
G01D02*
Y367875D01*
G01X127956Y261667D02*
X81086Y308537D01*
G01D02*
G02X79799Y311644I3107J3107D01*
G01D02*
Y375915D01*
G01X119554Y268229D02*
X80166Y307617D01*
G01D02*
G02X78499Y311643I4028J4026D01*
G01D02*
Y375914D01*
G01X61299Y346253D02*
G03X60099Y349150I-4097J0D01*
G01D02*
X32222Y377027D01*
G01D02*
X32196Y377052D01*
G01D02*
G03X28499Y378584I-3698J-3697D01*
G01D02*
X22385D01*
G01D02*
G02X21346Y378865I-1J2059D01*
G01D02*
G02X20929Y379187I1040J1777D01*
G01D02*
G03X19157Y379921I-1772J-1772D01*
G01D02*
X19151Y379915D01*
G01X59999Y346252D02*
G03X59673Y347562I-2796J0D01*
G01D02*
G03X59179Y348230I-2470J-1310D01*
G01D02*
X38242Y369167D01*
G01D02*
G03X37272Y369490I-798J-778D01*
G01D02*
G02X36301Y369814I-172J1102D01*
G01D02*
X35506Y370609D01*
G01D02*
G02X35182Y371580I778J799D01*
G01D02*
G03X34859Y372550I-1102J172D01*
G01D02*
X31304Y376105D01*
G01D02*
X31294Y376114D01*
G01D02*
X31276Y376132D01*
G01D02*
G03X28498Y377284I-2779J-2776D01*
G01D02*
X23000D01*
G01D02*
G03X20991Y376510I0J-2994D01*
G01D02*
G02X19671Y375999I-1319J1448D01*
G01X64999Y352757D02*
G03X63886Y355444I-3800J0D01*
G01D02*
X34052Y385278D01*
G01D02*
G03X31365Y386391I-2687J-2687D01*
G01D02*
X28499D01*
G01D02*
G02X26857Y387071I0J2322D01*
G01D02*
X26299Y387629D01*
G01X63699Y352756D02*
G03X62967Y354524I-2500J0D01*
G01D02*
X39131Y378360D01*
G01D02*
G03X38160Y378684I-799J-778D01*
G01D02*
G02X37190Y379007I-172J1102D01*
G01D02*
X36394Y379803D01*
G01D02*
G02X36071Y380773I778J798D01*
G01D02*
G03X35747Y381744I-1102J172D01*
G01D02*
X33132Y384359D01*
G01D02*
G03X31364Y385091I-1768J-1768D01*
G01D02*
X28399D01*
G01D02*
G03X26926Y384481I0J-2083D01*
G01D02*
X26299Y383854D01*
G01X19664Y395663D02*
X19670Y395669D01*
G01D02*
G02X20539Y395309I0J-1229D01*
G01D02*
X21199Y394650D01*
G01D02*
G03X21967Y394332I768J768D01*
G01D02*
X29209D01*
G01D02*
G02X33149Y392700I0J-5572D01*
G01D02*
X67000Y358849D01*
G01D02*
G02X68699Y354748I-4101J-4101D01*
G01X19494Y391726D02*
X19500Y391732D01*
G01D02*
G03X19889Y391893I0J550D01*
G01D02*
X20766Y392770D01*
G01D02*
G02X21399Y393032I633J-633D01*
G01D02*
X29209D01*
G01D02*
G02X32229Y391781I0J-4272D01*
G01D02*
X66081Y357929D01*
G01D02*
G02X67399Y354747I-3182J-3182D01*
G01X33944Y400145D02*
X70262Y363827D01*
G01D02*
G02X72399Y358665I-5163J-5161D01*
G01X31605Y400644D02*
X69342Y362907D01*
G01D02*
G02X71099Y358665I-4242J-4242D01*
G01X76099Y367876D02*
G03X74986Y370563I-3800J0D01*
G01D02*
X36248Y409301D01*
G01X74799Y367875D02*
G03X74067Y369643I-2500J0D01*
G01D02*
X35329Y408381D01*
G01X79799Y375915D02*
G03X78686Y378602I-3800J0D01*
G01D02*
X33143Y424145D01*
G01X78499Y375914D02*
G03X77767Y377682I-2500J0D01*
G01D02*
X32224Y423225D01*
G01X19727Y450783D02*
X19733Y450789D01*
G01D02*
G02X20585Y450436I0J-1205D01*
G01D02*
X21135Y449886D01*
G01D02*
G03X22069Y449499I934J934D01*
G01D02*
X35935D01*
G01D02*
G03X39117Y450817I0J4500D01*
G01D02*
X48801Y460501D01*
G01D02*
G02X52902Y462200I4101J-4101D01*
G01D02*
X176044D01*
G01X19827Y446852D02*
G03X20583Y447165I0J1069D01*
G01D02*
X21083Y447665D01*
G01D02*
G02X21424Y447933I1289J-1289D01*
G01D02*
G02X22372Y448199I948J-1557D01*
G01D02*
X35936D01*
G01D02*
G03X40037Y449898I0J5800D01*
G01D02*
X49721Y459582D01*
G01D02*
G02X52903Y460900I3182J-3182D01*
G01D02*
X176046D01*
G01X26799Y458497D02*
G03X28037Y457259I1238J0D01*
G01D02*
X34795D01*
G01D02*
G03X37977Y458577I0J4500D01*
G01D02*
X43701Y464301D01*
G01D02*
G02X47802Y466000I4101J-4101D01*
G01D02*
X172225D01*
G01X26899Y454850D02*
G02X28008Y455959I1109J0D01*
G01D02*
X34796D01*
G01D02*
G03X38897Y457658I0J5800D01*
G01D02*
X44621Y463382D01*
G01D02*
G02X47803Y464700I3182J-3182D01*
G01D02*
X172226D01*
G01X19410Y435035D02*
X19416Y435041D01*
G01D02*
G02X20811Y434463I0J-1973D01*
G01D02*
X21061Y434213D01*
G01D02*
G03X22290Y433704I1229J1229D01*
G01D02*
X67499D01*
G01D02*
G02X71228Y432160I1J-5273D01*
G01D02*
X71368Y432019D01*
G01D02*
X73918Y429469D01*
G01D02*
X73944Y429442D01*
G01D02*
G03X76099Y428550I2154J2155D01*
G01D02*
X81625D01*
G01D02*
G03X83393Y429282I0J2500D01*
G01D02*
X86634Y432523D01*
G01D02*
G02X89321Y433636I2687J-2687D01*
G01D02*
X276099D01*
G01X19787Y431098D02*
X19793Y431104D01*
G01D02*
G03X20607Y431441I0J1151D01*
G01D02*
X21157Y431991D01*
G01D02*
G02X22154Y432404I997J-997D01*
G01D02*
X67583D01*
G01D02*
G02X70248Y431300I0J-3769D01*
G01D02*
X72698Y428850D01*
G01D02*
X73024Y428523D01*
G01D02*
G03X76099Y427250I3074J3075D01*
G01D02*
X81626D01*
G01D02*
G03X84313Y428363I0J3800D01*
G01D02*
X87554Y431604D01*
G01D02*
G02X89322Y432336I1768J-1768D01*
G01D02*
X276099D01*
G01X26599Y442749D02*
G03X29126Y441512I2601J2113D01*
G01D02*
X162266D01*
G01X26492Y439350D02*
G02X29099Y440212I2607J-3511D01*
G01D02*
X162266D01*
G01X26299Y403376D02*
X27162Y402513D01*
G01D02*
G03X28067Y402138I905J905D01*
G01D02*
X31141D01*
G01D02*
G02X31789Y402027I0J-1947D01*
G01D02*
G02X32524Y401564I-654J-1853D01*
G01D02*
X33944Y400145D01*
G01X26299Y399601D02*
G02X27536Y400838I1237J0D01*
G01D02*
X31136D01*
G01D02*
G02X31605Y400644I0J-664D01*
G01X26515Y480944D02*
G02X25744Y480467I-533J0D01*
G01D02*
G03X23699Y480948I-2042J-4094D01*
G01X26299Y478404D02*
X26014Y478689D01*
G01D02*
G03X23699Y479648I-2315J-2315D01*
G01D02*
X21614D01*
G01D02*
G03X20503Y479188I0J-1571D01*
G01D02*
X19991Y478675D01*
G01D02*
G02X19200Y478348I-790J791D01*
G01D02*
X19194Y478342D01*
G01X26499Y466250D02*
Y465828D01*
G01D02*
G02X26130Y465093I-916J0D01*
G01D02*
G02X25510Y464836I-620J620D01*
G01D02*
X22000D01*
G01D02*
G02X21085Y465215I0J1294D01*
G01D02*
X20500Y465800D01*
G01D02*
G03X18735Y466531I-1765J-1765D01*
G01X26486Y462648D02*
G03X24342Y463536I-2144J-2144D01*
G01D02*
X21287D01*
G01D02*
G03X20172Y463074I0J-1577D01*
G01D02*
X19908Y462811D01*
G01D02*
G02X19400Y462600I-509J508D01*
G01D02*
X19394Y462594D01*
G01X36248Y409301D02*
G03X34174Y410160I-2074J-2074D01*
G01D02*
X22699D01*
G01D02*
G02X21504Y410655I0J1690D01*
G01D02*
X21304Y410855D01*
G01D02*
G03X19947Y411417I-1357J-1357D01*
G01X35329Y408381D02*
G03X34173Y408860I-1156J-1156D01*
G01D02*
X22318D01*
G01D02*
G03X21449Y408500I0J-1229D01*
G01D02*
X20849Y407900D01*
G01D02*
G02X19835Y407480I-1014J1014D01*
G01D02*
X19829Y407474D01*
G01X33143Y424145D02*
X33144Y424146D01*
G01D02*
X32065Y425224D01*
G01D02*
G03X30530Y425859I-1534J-1535D01*
G01D02*
X28499D01*
G01D02*
G02X26598Y426647I1J2689D01*
G01D02*
X26524Y426720D01*
G01X32224Y423225D02*
Y423224D01*
G01D02*
X31304Y424145D01*
G01D02*
Y424146D01*
G01D02*
X31146Y424304D01*
G01D02*
G03X30531Y424559I-615J-615D01*
G01D02*
X27099D01*
G01D02*
G03X26399Y423859I0J-700D01*
G01D02*
Y423322D01*
G01X192400Y764246D02*
X28031Y522175D01*
G01D02*
G03X27754Y521832I1484J-1482D01*
G01D02*
X27740Y521811D01*
G01D02*
G03X27199Y519980I2825J-1830D01*
G01D02*
Y515937D01*
G01D02*
G02X26441Y514107I-2588J0D01*
G01D02*
X25329Y512995D01*
G01D02*
G02X24922Y512686I-1330J1330D01*
G01D02*
G02X24135Y512360I-787J787D01*
G01D02*
X21616D01*
G01D02*
G02X20906Y512654I0J1004D01*
G01D02*
X20330Y513230D01*
G01D02*
G03X19000Y513781I-1330J-1330D01*
G01D02*
X18994Y513775D01*
G01X193499Y763550D02*
X29104Y521441D01*
G01D02*
G03X28499Y519980I1460J-1460D01*
G01D02*
Y515938D01*
G01D02*
G02X27360Y513188I-3888J-1D01*
G01D02*
Y513187D01*
G01D02*
X26861Y512688D01*
G01D02*
X26602Y512430D01*
G01D02*
G02X26058Y511968I-3104J3103D01*
G01D02*
G02X23866Y511060I-2192J2192D01*
G01D02*
X22170D01*
G01D02*
G03X21453Y510763I0J-1014D01*
G01D02*
X21222Y510531D01*
G01D02*
X20942Y510251D01*
G01D02*
G02X19959Y509844I-983J983D01*
G01X36499Y521550D02*
Y521451D01*
G01D02*
G03X37136Y519913I2175J0D01*
G01D02*
G03X38136I500J500D01*
G01D02*
X39196Y520973D01*
G01D02*
X39487Y521259D01*
G01D02*
Y521271D01*
G01D02*
X83417Y580774D01*
G01X84499Y580050D02*
X40409Y520331D01*
G01D02*
X40398Y520330D01*
G01D02*
X40108Y520045D01*
G01D02*
X38785Y518722D01*
G01D02*
G02X36499Y517775I-2286J2286D01*
G01X26599Y529302D02*
X25765Y528468D01*
G01D02*
G02X25099Y528192I-666J666D01*
G01D02*
X21999D01*
G01D02*
G02X20648Y528751I-1J1910D01*
G01D02*
X20275Y529125D01*
G01D02*
G03X19300Y529529I-975J-975D01*
G01D02*
X19294Y529523D01*
G01X26599Y525648D02*
X26031Y526216D01*
G01D02*
G03X24399Y526892I-1632J-1632D01*
G01D02*
X22699D01*
G01D02*
G03X20771Y526094I-1J-2726D01*
G01D02*
G02X19559Y525592I-1212J1212D01*
G01D02*
X19553Y525586D01*
G01X834716Y1457033D02*
X74101Y529547D01*
G01D02*
X74082Y529529D01*
G01D02*
X74076Y529521D01*
G01D02*
X43827Y499272D01*
G01D02*
G02X36991Y496696I-6923J8015D01*
G01D02*
X22788D01*
G01D02*
G02X20707Y497558I0J2943D01*
G01D02*
G03X19560Y498033I-1147J-1147D01*
G01D02*
X19554Y498027D01*
G01X835640Y1456108D02*
X75106Y528722D01*
G01D02*
X75021Y528627D01*
G01D02*
X44714Y498320D01*
G01D02*
G02X36997Y495396I-7810J8967D01*
G01D02*
X22573D01*
G01D02*
G03X20861Y494687I0J-2421D01*
G01D02*
X20711Y494537D01*
G01D02*
G02X19646Y494096I-1065J1065D01*
G01D02*
X19640Y494090D01*
G01X26399Y505741D02*
X26674Y505466D01*
G01D02*
G03X28999Y504503I2325J2325D01*
G01D02*
X37761D01*
G01D02*
G03X44054Y506945I-59J9482D01*
G01D02*
X64279Y527169D01*
G01D02*
X64293Y527185D01*
G01D02*
X65632Y528694D01*
G01D02*
X66651Y529934D01*
G01D02*
X68290Y531957D01*
G01D02*
X404830Y947194D01*
G01X26399Y501966D02*
G02X27636Y503203I1237J0D01*
G01D02*
X37765D01*
G01D02*
G03X44951Y506002I-62J10783D01*
G01D02*
Y506003D01*
G01D02*
X65198Y526249D01*
G01D02*
X65252Y526306D01*
G01D02*
X66621Y527849D01*
G01D02*
X67656Y529107D01*
G01D02*
X67662Y529115D01*
G01D02*
X405841Y946376D01*
G01X26515Y481798D02*
Y480944D01*
G01X23699Y480948D02*
X21657D01*
G01D02*
G02X20486Y481433I0J1656D01*
G01D02*
X19800Y482120D01*
G01D02*
G03X19400Y482285I-399J-400D01*
G01D02*
X19394Y482279D01*
G01X83417Y580774D02*
X125168Y649909D01*
G01X125902Y648609D02*
X84499Y580050D01*
G01X62199Y668554D02*
Y636879D01*
G01D02*
G02X60579Y632970I-5527J1D01*
G01D02*
G02X54748Y630554I-5831J5829D01*
G01D02*
X22867D01*
G01D02*
G02X20596Y631494I-1J3211D01*
G01D02*
G03X19638Y631891I-958J-958D01*
G01D02*
X19632Y631885D01*
G01X63499Y668555D02*
Y636878D01*
G01D02*
G02X61499Y632050I-6828J0D01*
G01D02*
G02X54749Y629254I-6750J6750D01*
G01D02*
X22828D01*
G01D02*
G03X20737Y628388I0J-2957D01*
G01D02*
G02X19689Y627954I-1048J1048D01*
G01D02*
X19683Y627948D01*
G01X58199Y670640D02*
Y644379D01*
G01D02*
G02X56579Y640470I-5527J1D01*
G01D02*
G02X51650Y638427I-4931J4929D01*
G01D02*
X29410D01*
G01D02*
G02X26568Y639604I0J4019D01*
G01Y635950D02*
G02X29410Y637127I2842J-2842D01*
G01D02*
X51649D01*
G01D02*
G03X57499Y639550I0J8273D01*
G01D02*
G03X59499Y644378I-4828J4828D01*
G01D02*
Y670641D01*
G01X53531Y646970D02*
G02X51918Y646302I-1613J1613D01*
G01D02*
X22867D01*
G01D02*
G02X21121Y646834I1J3134D01*
G01X55499Y648582D02*
G02X54450Y646050I-3580J0D01*
G01D02*
G02X51920Y645002I-2530J2530D01*
G01D02*
X21617D01*
G01D02*
G03X20651Y644602I0J-1366D01*
G01D02*
G02X18478Y643702I-2173J2173D01*
G01D02*
X18472Y643696D01*
G01X70699Y666977D02*
Y634499D01*
G01D02*
X70698Y634500D01*
G01D02*
G02X66872Y625262I-13065J0D01*
G01D02*
X61079Y619469D01*
G01D02*
X61078D01*
G01D02*
X60803Y619194D01*
G01D02*
G02X50213Y614806I-10592J10590D01*
G01D02*
X21508D01*
G01D02*
G02X20484Y615230I0J1448D01*
G01D02*
G03X18280Y616143I-2204J-2204D01*
G01D02*
X18274Y616137D01*
G01X71999Y666977D02*
Y634500D01*
G01D02*
G02X67792Y624342I-14365J-1D01*
G01D02*
X61723Y618274D01*
G01D02*
G02X50212Y613506I-11511J11511D01*
G01D02*
X21440D01*
G01D02*
G03X20537Y613132I0J-1277D01*
G01D02*
G02X18301Y612206I-2236J2236D01*
G01D02*
X18295Y612200D01*
G01X27499Y623857D02*
G03X30341Y622680I2842J2842D01*
G01D02*
X47689D01*
G01D02*
G03X64079Y629470I-1J23179D01*
G01D02*
G03X66198Y634586I-5116J5116D01*
G01D02*
X66199Y634585D01*
G01D02*
Y667157D01*
G01X27499Y620203D02*
G02X30341Y621380I2842J-2842D01*
G01D02*
X47689D01*
G01D02*
G03X64999Y628550I0J24480D01*
G01D02*
G03X67499Y634586I-6036J6036D01*
G01D02*
Y667156D01*
G01X18459Y584641D02*
X18465Y584647D01*
G01D02*
G02X20474Y583815I0J-2841D01*
G01D02*
G03X21693Y583310I1219J1219D01*
G01D02*
X28860D01*
G01D02*
G03X31249Y584300I0J3377D01*
G01D02*
X36998Y590049D01*
G01D02*
Y590050D01*
G01D02*
X82572Y635624D01*
G01D02*
G03X84199Y639551I-3926J3927D01*
G01D02*
Y641514D01*
G01D02*
G02X87080Y648470I9836J1D01*
G01X87999Y647550D02*
G03X85499Y641514I6036J-6036D01*
G01D02*
Y639550D01*
G01D02*
G02X83492Y634704I-6854J0D01*
G01D02*
X32168Y583380D01*
G01D02*
G02X28861Y582010I-3307J3307D01*
G01D02*
X21493D01*
G01D02*
G03X20472Y581587I0J-1444D01*
G01D02*
G02X18355Y580710I-2117J2117D01*
G01D02*
X18349Y580704D01*
G01X134581Y744167D02*
X64481Y674067D01*
G01D02*
X64482Y674066D01*
G01D02*
G03X62199Y668554I5511J-5511D01*
G01X135501Y743247D02*
X65401Y673147D01*
G01D02*
G03X63499Y668555I4592J-4592D01*
G01X130499Y746550D02*
X60749Y676800D01*
G01D02*
X60750Y676799D01*
G01D02*
G03X58199Y670640I6158J-6158D01*
G01X59499Y670641D02*
G02X61669Y675880I7409J0D01*
G01D02*
X131419Y745630D01*
G01X117329Y742919D02*
X57729Y683319D01*
G01D02*
X57730D01*
G01D02*
G03X54199Y674794I8524J-8524D01*
G01D02*
Y648583D01*
G01D02*
G02X53531Y646970I-2281J0D01*
G01X21121Y646834D02*
G03X20640Y647216I-1899J-1897D01*
G01D02*
G03X19619Y647639I-1021J-1021D01*
G01D02*
X19613Y647633D01*
G01X118248Y741999D02*
X58649Y682400D01*
G01D02*
G03X55499Y674795I7605J-7605D01*
G01D02*
Y648582D01*
G01X26999Y656550D02*
Y655757D01*
G01D02*
G03X27499Y654550I1707J0D01*
G01D02*
G03X27982Y654350I483J483D01*
G01D02*
X46584D01*
G01D02*
G03X48079Y654970I0J2113D01*
G01D02*
G03X49699Y658879I-3907J3910D01*
G01D02*
Y678813D01*
G01D02*
G02X52200Y684849I8538J-2D01*
G01D02*
X52199Y684850D01*
G01D02*
X114499Y747150D01*
G01X26737Y651957D02*
G02X29376Y653050I2639J-2639D01*
G01D02*
X46585D01*
G01D02*
G03X48999Y654050I0J3414D01*
G01D02*
G03X50999Y658878I-4828J4828D01*
G01D02*
Y678812D01*
G01D02*
G02X53119Y683930I7238J0D01*
G01D02*
X115419Y746230D01*
G01X102941Y741832D02*
X48329Y687220D01*
G01D02*
X48330Y687219D01*
G01D02*
G03X44699Y678455I8765J-8766D01*
G01D02*
Y666550D01*
G01D02*
G02X40199Y662050I-4500J0D01*
G01D02*
X22577D01*
G01D02*
G02X21701Y662412I-1J1238D01*
G01D02*
X21339Y662775D01*
G01D02*
G03X19862Y663387I-1477J-1477D01*
G01X19162Y659444D02*
X19168Y659450D01*
G01D02*
G03X21099Y660250I0J2731D01*
G01D02*
G02X22306Y660750I1207J-1207D01*
G01D02*
X40199D01*
G01D02*
G03X45999Y666550I0J5800D01*
G01D02*
Y678454D01*
G01D02*
G02X49249Y686300I11096J0D01*
G01D02*
X103861Y740912D01*
G01X27687Y671101D02*
G03X29500Y670350I1813J1813D01*
G01D02*
X34999D01*
G01D02*
G03X38199Y673550I0J3200D01*
G01D02*
Y687170D01*
G01D02*
G02X40496Y695052I14680J-2D01*
G01D02*
G02X42499Y697549I12384J-7882D01*
G01D02*
X42498D01*
G01D02*
X98699Y753750D01*
G01X27687Y667447D02*
Y667738D01*
G01D02*
G02X28999Y669050I1312J0D01*
G01D02*
X34999D01*
G01D02*
G03X39499Y673550I0J4500D01*
G01D02*
Y687169D01*
G01D02*
G02X41592Y694354I13380J0D01*
G01D02*
G02X43418Y696630I11287J-7185D01*
G01D02*
X99618Y752830D01*
G01X141679Y739769D02*
X71980Y670070D01*
G01D02*
G03X70699Y666977I3092J-3092D01*
G01X142599Y738850D02*
X72899Y669150D01*
G01D02*
G03X71999Y666977I2173J-2173D01*
G01X66199Y667157D02*
G02X68598Y672949I8193J-1D01*
G01D02*
X138849Y743200D01*
G01X67499Y667156D02*
G02X69518Y672030I6893J0D01*
G01D02*
X139768Y742280D01*
G01X87080Y648470D02*
X87079D01*
G01D02*
X147079Y708470D01*
G01X147999Y707550D02*
X87999Y647550D01*
G01X76999Y664550D02*
G03X77471Y665690I-1140J1140D01*
G01D02*
Y667851D01*
G01D02*
G02X78379Y669930I3108J-120D01*
G01D02*
X78399Y669950D01*
G01D02*
X81498Y673050D01*
G01D02*
G02X83915Y674050I2416J-2418D01*
G01D02*
X90456D01*
G01D02*
G03X92112Y674736I0J2342D01*
G01D02*
X129261Y711885D01*
G01X147032Y727817D02*
X93031Y673816D01*
G01D02*
G02X90457Y672750I-2575J2576D01*
G01D02*
X83915D01*
G01D02*
G03X82418Y672130I0J-2117D01*
G01D02*
X79299Y669010D01*
G01D02*
G03X78768Y667799I1278J-1282D01*
G01D02*
Y665608D01*
G01D02*
G03X78999Y665050I789J0D01*
G01D02*
G03X80206Y664550I1207J1207D01*
G01D02*
X80499D01*
G01X93330Y753669D02*
X35580Y695919D01*
G01D02*
X35581D01*
G01D02*
G03X33700Y691380I4540J-4541D01*
G01D02*
Y684500D01*
G01D02*
G02X32427Y681427I-4346J0D01*
G01D02*
X30500Y679500D01*
G01D02*
G02X26437Y677817I-4063J4063D01*
G01D02*
X21535D01*
G01D02*
G02X20569Y678217I0J1366D01*
G01D02*
G03X18353Y679135I-2216J-2216D01*
G01D02*
X18347Y679129D01*
G01X18982Y675192D02*
X18988Y675198D01*
G01D02*
G03X20200Y675700I0J1714D01*
G01D02*
X20650Y676151D01*
G01D02*
G02X21533Y676516I883J-886D01*
G01D02*
G03X21536Y676517I-842J2531D01*
G01D02*
X26438D01*
G01D02*
G03X31419Y678581I-2J7046D01*
G01D02*
Y678580D01*
G01D02*
X32919Y680080D01*
G01D02*
X32920D01*
G01D02*
X33347Y680507D01*
G01D02*
G03X35000Y684499I-3994J3992D01*
G01D02*
Y691379D01*
G01D02*
G02X36500Y695000I5121J0D01*
G01D02*
X94249Y752749D01*
G01X94800Y836500D02*
Y757218D01*
G01D02*
G02X93330Y753669I-5019J0D01*
G01X94249Y752749D02*
Y752750D01*
G01D02*
G03X96100Y757219I-4468J4468D01*
G01X59200Y1325112D02*
Y878499D01*
G01D02*
G03X61816Y872182I8935J0D01*
G01D02*
X62059Y871939D01*
G01D02*
X62060Y871940D01*
G01D02*
X92891Y841109D01*
G01D02*
G02X94800Y836500I-4609J-4609D01*
G01X96100Y836499D02*
G03X93811Y842029I-7819J2D01*
G01D02*
X93170Y842670D01*
G01D02*
X93169Y842669D01*
G01D02*
Y842671D01*
G01D02*
X67170Y868670D01*
G01D02*
X62979Y872860D01*
G01D02*
X62978Y872859D01*
G01D02*
X62736Y873102D01*
G01D02*
G02X60500Y878500I5398J5398D01*
G01D02*
Y1325111D01*
G01X99899Y929150D02*
X91249Y937800D01*
G01D02*
G03X89262Y938623I-1987J-1987D01*
G01D02*
X87058D01*
G01D02*
G03X86399Y938350I0J-932D01*
G01D02*
G03Y937050I650J-650D01*
G01X100818Y930070D02*
X92169Y938719D01*
G01D02*
G03X89262Y939923I-2906J-2906D01*
G01D02*
X87221D01*
G01D02*
G02X85999Y940429I0J1728D01*
G01X95687Y1054411D02*
G02X93779Y1059021I4610J4608D01*
G01D02*
Y1316719D01*
G01X96384Y1362842D02*
X93644D01*
G01D02*
X93638Y1362836D01*
G01D02*
X22133D01*
G01D02*
G02X20897Y1363348I0J1748D01*
G01D02*
G03X18905Y1364173I-1992J-1992D01*
G01D02*
X18899Y1364167D01*
G01X96745Y1361536D02*
X22165D01*
G01D02*
G03X21187Y1361131I0J-1383D01*
G01D02*
G02X19026Y1360236I-2161J2161D01*
G01D02*
X19020Y1360230D01*
G01X95999Y1382550D02*
G03X92585Y1381136I0J-4828D01*
G01D02*
X83499Y1372050D01*
G01D02*
G02X80279Y1370716I-3221J3221D01*
G01D02*
X28499D01*
G01D02*
G02X25660Y1371892I0J4015D01*
G01D02*
X25507Y1372045D01*
G01X95998Y1381250D02*
G03X93505Y1380216I2J-3527D01*
G01D02*
X84419Y1371130D01*
G01D02*
G02X80278Y1369416I-4139J4142D01*
G01D02*
X72256D01*
G01D02*
G03X71341Y1368958I-14J-1115D01*
G01D02*
G02X70426Y1368501I-900J658D01*
G01D02*
X69301D01*
G01D02*
G02X68386Y1368958I-15J1115D01*
G01D02*
G03X67471Y1369416I-901J-657D01*
G01D02*
X54526D01*
G01D02*
G03X53611Y1368958I-14J-1115D01*
G01D02*
G02X52696Y1368501I-900J658D01*
G01D02*
X51571D01*
G01D02*
G02X50656Y1368958I-15J1115D01*
G01D02*
G03X49741Y1369416I-901J-657D01*
G01D02*
X48616D01*
G01D02*
G03X47701Y1368958I-14J-1115D01*
G01D02*
G02X46786Y1368501I-900J658D01*
G01D02*
X45661D01*
G01D02*
G02X44746Y1368958I-15J1115D01*
G01D02*
G03X43831Y1369416I-901J-657D01*
G01D02*
X42706D01*
G01D02*
G03X41791Y1368958I-14J-1115D01*
G01D02*
G02X40876Y1368501I-900J658D01*
G01D02*
X39751D01*
G01D02*
G02X38836Y1368958I-15J1115D01*
G01D02*
G03X37921Y1369416I-901J-657D01*
G01D02*
X36796D01*
G01D02*
G03X35881Y1368958I-14J-1115D01*
G01D02*
G02X34966Y1368501I-900J658D01*
G01D02*
X33841D01*
G01D02*
G02X32926Y1368958I-15J1115D01*
G01D02*
G03X32011Y1369416I-901J-657D01*
G01D02*
X27897D01*
G01D02*
G03X25558Y1368447I0J-3308D01*
G01X93779Y1316719D02*
G03X93322Y1317634I-1115J15D01*
G01D02*
G02X92864Y1318549I657J901D01*
G01D02*
Y1319674D01*
G01D02*
G02X93321Y1320589I1115J15D01*
G01D02*
G03X93779Y1321504I-657J901D01*
G01D02*
Y1322629D01*
G01D02*
G03X93322Y1323544I-1115J15D01*
G01D02*
G02X92864Y1324459I657J901D01*
G01D02*
Y1325584D01*
G01D02*
G02X93321Y1326499I1115J15D01*
G01D02*
G03X93779Y1327414I-657J901D01*
G01D02*
Y1342442D01*
G01D02*
G03X93079Y1344130I-2386J0D01*
G01D02*
G03X92791Y1344250I-288J-286D01*
G01D02*
X90246D01*
G01D02*
G03X86890Y1342860I0J-4746D01*
G01X95079Y1342443D02*
G03X93999Y1345050I-3687J0D01*
G01D02*
G03X92792Y1345550I-1207J-1207D01*
G01D02*
X89509D01*
G01D02*
G02X86890Y1346635I0J3704D01*
G01X19953Y1379921D02*
G02X21143Y1379428I0J-1683D01*
G01D02*
X21277Y1379294D01*
G01D02*
G03X22699Y1378705I1422J1422D01*
G01D02*
X26610D01*
G01D02*
G03X28392Y1379443I0J2520D01*
G01D02*
X28796Y1379847D01*
G01D02*
G03X29499Y1381544I-1697J1697D01*
G01D02*
Y1389500D01*
G01D02*
G03X29110Y1390439I-1328J0D01*
G01D02*
X28499Y1391050D01*
G01X18519Y1375978D02*
X18525Y1375984D01*
G01D02*
G03X21099Y1377050I0J3640D01*
G01D02*
G02X21659Y1377367I855J-858D01*
G01D02*
G02X21696Y1377376I305J-1173D01*
G01D02*
G02X21956Y1377405I264J-1183D01*
G01D02*
X26610D01*
G01D02*
G03X29312Y1378523I1J3821D01*
G01D02*
X29716Y1378927D01*
G01D02*
G03X30799Y1381544I-2617J2616D01*
G01D02*
Y1387347D01*
G01D02*
G02X31154Y1388204I1212J0D01*
G01D02*
X32333Y1389383D01*
G01X97130Y1355208D02*
G03X94494Y1356300I-2636J-2636D01*
G01D02*
X89327D01*
G01D02*
G03X83581Y1353919I2J-8128D01*
G01D02*
X83580D01*
G01D02*
X62330Y1332669D01*
G01D02*
X62331D01*
G01D02*
G03X59200Y1325112I7558J-7558D01*
G01X60500Y1325111D02*
G02X63250Y1331750I9389J0D01*
G01D02*
X84500Y1353000D01*
G01D02*
G02X89328Y1355000I4828J-4828D01*
G01D02*
X94486D01*
G01D02*
G02X96216Y1354283I0J-2445D01*
G01X28999Y1411550D02*
X29280Y1411269D01*
G01D02*
G02X30199Y1409050I-2219J-2219D01*
G01D02*
Y1401946D01*
G01D02*
X30198Y1401947D01*
G01D02*
G02X28999Y1399049I-4098J-2D01*
G01D02*
X28998D01*
G01D02*
X25197Y1395248D01*
G01D02*
X24839Y1394889D01*
G01D02*
G02X23988Y1394537I-851J852D01*
G01D02*
X23201D01*
G01D02*
X23188Y1394550D01*
G01D02*
X22281D01*
G01D02*
G02X20946Y1395103I0J1888D01*
G01D02*
G03X19580Y1395669I-1366J-1366D01*
G01D02*
X19574Y1395663D01*
G01X32451Y1411468D02*
G03X31499Y1409170I2298J-2298D01*
G01D02*
Y1401947D01*
G01D02*
G02X29918Y1398130I-5398J0D01*
G01D02*
X26118Y1394330D01*
G01D02*
X25759Y1393970D01*
G01D02*
G02X23988Y1393237I-1770J1771D01*
G01D02*
X23201D01*
G01D02*
X23188Y1393224D01*
G01D02*
G03X21833Y1392547I340J-2375D01*
G01D02*
X21702Y1392416D01*
G01D02*
G02X20051Y1391732I-1651J1651D01*
G01X30499Y1434550D02*
G02X30840Y1433727I-823J-823D01*
G01D02*
Y1426050D01*
G01D02*
G02X29553Y1422943I-4394J0D01*
G01D02*
X26329Y1419719D01*
G01D02*
X25834Y1419225D01*
G01D02*
G02X22999Y1418050I-2836J2835D01*
G01D02*
X21864D01*
G01D02*
G02X20387Y1418662I0J2088D01*
G01D02*
G03X18864Y1419293I-1523J-1523D01*
G01D02*
X18858Y1419287D01*
G01X33206Y1432352D02*
G03X32140Y1429778I2574J-2574D01*
G01D02*
Y1426050D01*
G01D02*
G02X30473Y1422023I-5694J-1D01*
G01D02*
X27248Y1418799D01*
G01D02*
X26753Y1418305D01*
G01D02*
G02X22999Y1416751I-3753J3755D01*
G01D02*
Y1416750D01*
G01D02*
X22693D01*
G01D02*
G03X20996Y1416047I0J-2400D01*
G01D02*
G02X19328Y1415356I-1668J1668D01*
G01D02*
X19322Y1415350D01*
G01X99911Y1438138D02*
X53499Y1484550D01*
G01X55829Y1480380D02*
X98991Y1437218D01*
G01X101376Y1430972D02*
X51648Y1480700D01*
G01X100456Y1430052D02*
X89004Y1441504D01*
G01D02*
X49809Y1480700D01*
G01X31999Y1474810D02*
G02X30286Y1470677I-5847J2D01*
G01D02*
X25580Y1465971D01*
G01D02*
X25384Y1465776D01*
G01D02*
X25383Y1465775D01*
G01D02*
G02X23998Y1465200I-1386J1383D01*
G01D02*
X21736D01*
G01D02*
G02X20630Y1465658I0J1564D01*
G01D02*
G03X18508Y1466537I-2122J-2122D01*
G01D02*
X18502Y1466531D01*
G01X33299Y1474811D02*
G02X31206Y1469757I-7148J0D01*
G01D02*
X26499Y1465050D01*
G01D02*
X26303Y1464855D01*
G01D02*
G02X23999Y1463900I-2305J2304D01*
G01D02*
X21638D01*
G01D02*
G03X20721Y1463520I0J-1297D01*
G01D02*
G02X18500Y1462600I-2221J2221D01*
G01D02*
X18494Y1462594D01*
G01X30378Y1462518D02*
G02X30977Y1461319I-1500J-1498D01*
G01D02*
G02X30999Y1461019I-2098J-305D01*
G01D02*
Y1458050D01*
G01D02*
G02X29471Y1454361I-5217J0D01*
G01D02*
X26329Y1451219D01*
G01D02*
X25667Y1450556D01*
G01D02*
X25290Y1450178D01*
G01D02*
G02X23536Y1449452I-1754J1755D01*
G01D02*
X22443D01*
G01D02*
G02X22174Y1449469I-6J2042D01*
G01D02*
G02X20999Y1450050I270J2024D01*
G01D02*
G03X19215Y1450789I-1784J-1784D01*
G01D02*
X19209Y1450783D01*
G01X33915Y1462681D02*
G03X32575Y1462126I0J-1895D01*
G01D02*
X32499Y1462050D01*
G01D02*
G03X32299Y1461567I483J-483D01*
G01D02*
Y1458050D01*
G01D02*
G02X30391Y1453441I-6518J-1D01*
G01D02*
X26587Y1449637D01*
G01D02*
X26210Y1449259D01*
G01D02*
G02X23536Y1448152I-2673J2674D01*
G01D02*
X22273D01*
G01D02*
G03X20863Y1447568I0J-1994D01*
G01D02*
G02X19134Y1446852I-1729J1729D01*
G01D02*
X19128Y1446846D01*
G01X18940Y1435035D02*
X18946Y1435041D01*
G01D02*
G02X20411Y1434434I0J-2072D01*
G01D02*
G03X21831Y1433846I1420J1421D01*
G01D02*
X25100D01*
G01D02*
G03X26200Y1434946I0J1100D01*
G01D02*
Y1436500D01*
G01D02*
G02X26500Y1438500I6814J0D01*
G01D02*
G02X28055Y1440945I5228J-1608D01*
G01D02*
X29166Y1442056D01*
G01D02*
G03X30199Y1444550I-2494J2494D01*
G01D02*
Y1446050D01*
G01D02*
G03X29673Y1447320I-1796J0D01*
G01D02*
X28697Y1448296D01*
G01X32094Y1448448D02*
G03X31499Y1447012I1436J-1436D01*
G01D02*
Y1444550D01*
G01D02*
G02X30086Y1441136I-4828J-1D01*
G01D02*
X28951Y1440001D01*
G01D02*
G03X28928Y1439981I2724J-3156D01*
G01D02*
G03X27743Y1438118I2800J-3089D01*
G01D02*
X27742D01*
G01D02*
G03X27500Y1436500I5273J-1616D01*
G01D02*
Y1434946D01*
G01D02*
G02X25100Y1432546I-2400J0D01*
G01D02*
X22954D01*
G01D02*
G03X21257Y1431843I0J-2400D01*
G01D02*
G02X19473Y1431104I-1784J1784D01*
G01D02*
X19467Y1431098D01*
G01X30115Y1511900D02*
G02X30999Y1509766I-2134J-2134D01*
G01D02*
Y1505050D01*
G01D02*
G02X29920Y1502445I-3684J0D01*
G01D02*
X24728Y1497253D01*
G01D02*
G02X23031Y1496550I-1697J1697D01*
G01D02*
X22967D01*
G01D02*
G02X21270Y1497253I0J2400D01*
G01D02*
G03X19387Y1498033I-1883J-1883D01*
G01D02*
X19381Y1498027D01*
G01X33512Y1512051D02*
G03X32299Y1509123I2928J-2928D01*
G01D02*
Y1505050D01*
G01D02*
G02X30838Y1501523I-4988J0D01*
G01D02*
X25648Y1496333D01*
G01D02*
G02X23031Y1495250I-2616J2617D01*
G01D02*
X22967D01*
G01D02*
G02X22916I-25J3700D01*
G01D02*
X22501D01*
G01D02*
G03X21049Y1494648I0J-2052D01*
G01D02*
X21000Y1494600D01*
G01D02*
G02X19783Y1494096I-1217J1217D01*
G01X30499Y1497550D02*
G02X31499Y1495136I-2414J-2414D01*
G01D02*
Y1490050D01*
G01D02*
G02X30793Y1488344I-2412J-1D01*
G01D02*
X28676Y1486228D01*
G01D02*
X28012Y1485564D01*
G01D02*
G03X27154Y1483490I2075J-2073D01*
G01D02*
Y1483489D01*
G01D02*
G02X26804Y1482645I-1195J1D01*
G01D02*
X25704Y1481545D01*
G01D02*
X25653Y1481493D01*
G01D02*
G02X24099Y1480850I-1553J1554D01*
G01D02*
X21982D01*
G01D02*
G02X21499Y1481050I0J683D01*
G01D02*
X20974Y1481575D01*
G01D02*
G03X19260Y1482285I-1714J-1714D01*
G01D02*
X19254Y1482279D01*
G01X34099Y1497550D02*
X34001Y1497452D01*
G01D02*
G03X32799Y1494550I2902J-2902D01*
G01D02*
Y1490112D01*
G01D02*
G02X31667Y1487379I-3865J0D01*
G01D02*
X28932Y1484644D01*
G01D02*
G03X28453Y1483490I1154J-1155D01*
G01D02*
Y1483487D01*
G01D02*
G02X27723Y1481725I-2492J0D01*
G01D02*
X26632Y1480634D01*
G01D02*
X26578Y1480578D01*
G01D02*
G02X24099Y1479551I-2476J2470D01*
G01D02*
Y1479550D01*
G01D02*
X21887D01*
G01D02*
G03X21633Y1479520I1J-1096D01*
G01D02*
G03X21111Y1479228I256J-1070D01*
G01D02*
X20966Y1479083D01*
G01D02*
G02X19192Y1478348I-1774J1774D01*
G01D02*
X19186Y1478342D01*
G01X53499Y1484550D02*
X53327Y1484721D01*
G01D02*
G02X50499Y1491550I6829J6828D01*
G01D02*
Y1510053D01*
G01D02*
X50500D01*
G01D02*
G03X48151Y1515934I-8540J-2D01*
G01D02*
X48146Y1515944D01*
G01D02*
X40518Y1523571D01*
G01D02*
X40024Y1524064D01*
G01D02*
G03X35228Y1526051I-4797J-4798D01*
G01D02*
X33499D01*
G01D02*
G03X29508Y1524398I0J-5644D01*
G01D02*
X28475Y1523365D01*
G01D02*
G03X26480Y1518550I4815J-4816D01*
G01D02*
Y1515550D01*
G01D02*
G02X25740Y1513765I-2525J1D01*
G01D02*
X25292Y1513316D01*
G01D02*
X25265Y1513288D01*
G01D02*
G02X22999Y1512350I-2265J2266D01*
G01D02*
X22262D01*
G01D02*
G02X21255Y1512767I0J1424D01*
G01D02*
X20985Y1513037D01*
G01D02*
G03X19189Y1513781I-1796J-1796D01*
G01D02*
X19183Y1513775D01*
G01X19440Y1509838D02*
X19446Y1509844D01*
G01D02*
G03X20689Y1510359I0J1758D01*
G01D02*
G02X22357Y1511050I1668J-1668D01*
G01D02*
X22999D01*
G01D02*
G03X26194Y1512377I2J4505D01*
G01D02*
X26221Y1512405D01*
G01D02*
X26432Y1512616D01*
G01D02*
X26659Y1512842D01*
G01D02*
G03X27780Y1515550I-2708J2707D01*
G01D02*
Y1518549D01*
G01D02*
G02X29395Y1522445I5509J-1D01*
G01D02*
X30441Y1523491D01*
G01D02*
G02X33483Y1524751I3042J-3042D01*
G01D02*
X35227D01*
G01D02*
Y1524750D01*
G01D02*
G02X39105Y1523144I0J-5484D01*
G01D02*
X39599Y1522651D01*
G01D02*
X47077Y1515173D01*
G01D02*
X47078Y1515171D01*
G01D02*
G02X49199Y1510052I-5115J-5118D01*
G01D02*
G02Y1510050I-7245J-1D01*
G01D02*
Y1491550D01*
G01D02*
G03X52408Y1483803I10956J0D01*
G01D02*
X52409Y1483802D01*
G01D02*
X52635Y1483575D01*
G01D02*
X55829Y1480380D01*
G01X51648Y1480700D02*
X51649Y1480701D01*
G01D02*
X49400Y1482950D01*
G01D02*
X49130Y1483221D01*
G01D02*
X49126Y1483225D01*
G01D02*
G02X47173Y1486038I6830J6827D01*
G01D02*
X47172Y1486041D01*
G01D02*
G02X46302Y1489823I8784J4012D01*
G01D02*
X46301Y1489847D01*
G01D02*
G02X46299Y1490051I8568J186D01*
G01D02*
Y1508176D01*
G01D02*
G03X43759Y1514311I-8675J2D01*
G01D02*
X40008Y1518061D01*
G01D02*
X39334Y1518735D01*
G01D02*
G03X35499Y1520323I-3834J-3834D01*
G01D02*
X34499D01*
G01D02*
G02X32241Y1521259I1J3194D01*
G01D02*
X31999Y1521500D01*
G01X49809Y1480700D02*
X49810Y1480701D01*
G01D02*
X48479Y1482031D01*
G01D02*
X48209Y1482302D01*
G01D02*
G02X45988Y1485501I7747J7749D01*
G01D02*
G02X45002Y1489792I9969J4549D01*
G01D02*
G02X44999Y1490050I10955J256D01*
G01D02*
Y1508176D01*
G01D02*
G03X42839Y1513391I-7375J0D01*
G01D02*
X39089Y1517141D01*
G01D02*
X38414Y1517815D01*
G01D02*
G03X35499Y1519023I-2915J-2913D01*
G01D02*
X34499D01*
G01D02*
G03X32241Y1518087I1J-3194D01*
G01D02*
X31999Y1517846D01*
G01X30999Y1482050D02*
G02X31999Y1479636I-2414J-2414D01*
G01D02*
Y1474810D01*
G01X34465Y1481683D02*
X34336Y1481555D01*
G01D02*
G03X33299Y1479050I2505J-2504D01*
G01D02*
Y1474811D01*
G01X30579Y1642701D02*
Y1638549D01*
G01D02*
X30578Y1638550D01*
G01D02*
Y1638519D01*
G01D02*
G02X30554Y1638044I-4721J0D01*
G01D02*
G02X29108Y1634997I-4999J506D01*
G01D02*
X29079Y1634969D01*
G01D02*
X25829Y1631719D01*
G01D02*
X25482Y1631373D01*
G01D02*
G02X23821Y1630569I-1985J1982D01*
G01D02*
X22160D01*
G01D02*
G02X21086Y1631014I0J1519D01*
G01D02*
X20800Y1631300D01*
G01D02*
G03X19373Y1631891I-1427J-1427D01*
G01D02*
X19367Y1631885D01*
G01X31879Y1642282D02*
Y1638550D01*
G01D02*
G02X30026Y1634078I-6324J0D01*
G01D02*
X29999Y1634050D01*
G01D02*
X26748Y1630799D01*
G01D02*
X26401Y1630453D01*
G01D02*
G02X23972Y1629278I-2903J2903D01*
G01D02*
X22200D01*
G01D02*
G03X22174Y1629277I77J-2346D01*
G01D02*
X22092Y1629273D01*
G01D02*
G03X20539Y1628590I102J-2339D01*
G01D02*
G02X19004Y1627954I-1535J1535D01*
G01D02*
X18998Y1627948D01*
G01X29499Y1630050D02*
G02X30199Y1628360I-1690J-1690D01*
G01D02*
Y1622356D01*
G01D02*
G02X28596Y1618486I-5473J0D01*
G01D02*
X25648Y1615538D01*
G01D02*
G02X23958Y1614807I-1768J1769D01*
G01D02*
G02X23880Y1614806I-71J2500D01*
G01D02*
X21747D01*
G01D02*
G02X20617Y1615274I0J1598D01*
G01D02*
G03X18519Y1616143I-2098J-2098D01*
G01D02*
X18513Y1616137D01*
G01X32663Y1628181D02*
X32183Y1627701D01*
G01D02*
G03X31698Y1626994I1650J-1652D01*
G01D02*
G03X31499Y1626050I2136J-943D01*
G01D02*
Y1622550D01*
G01D02*
G02X29378Y1617428I-7243J-1D01*
G01D02*
X29315Y1617366D01*
G01D02*
X26999Y1615050D01*
G01D02*
Y1615049D01*
G01D02*
X26568Y1614618D01*
G01D02*
G02X23997Y1613507I-2688J2689D01*
G01D02*
G02X23879Y1613506I-91J3800D01*
G01D02*
X21710D01*
G01D02*
G03X20625Y1613056I1J-1535D01*
G01D02*
X20624D01*
G01D02*
G02X18572Y1612206I-2052J2052D01*
G01D02*
X18566Y1612200D01*
G01X28899Y1613524D02*
X29518Y1612906D01*
G01D02*
G02X30079Y1611550I-1356J-1355D01*
G01D02*
Y1603950D01*
G01D02*
G02X29499Y1602550I-1980J0D01*
G01D02*
X27779Y1600830D01*
G01D02*
G02X22999Y1598850I-4780J4780D01*
G01D02*
X21723D01*
G01D02*
G02X20655Y1599293I1J1511D01*
G01D02*
X20654D01*
G01D02*
G03X17994Y1600395I-2660J-2660D01*
G01D02*
X17988Y1600389D01*
G01X32299Y1613524D02*
X32111Y1613336D01*
G01D02*
G03X31379Y1611568I1769J-1768D01*
G01D02*
Y1603949D01*
G01D02*
G02X30419Y1601630I-3280J0D01*
G01D02*
X28699Y1599910D01*
G01D02*
G02X24830Y1597760I-5699J5700D01*
G01D02*
G02X22999Y1597550I-1828J7851D01*
G01D02*
X21499D01*
G01D02*
G03X20944Y1597320I0J-785D01*
G01D02*
G02X18863Y1596458I-2081J2081D01*
G01D02*
X18857Y1596452D01*
G01X27123Y1572205D02*
G02X28012Y1569771I-1592J-1961D01*
G01D02*
G02X26856Y1568094I-2481J473D01*
G01D02*
G02X26573Y1567937I-1859J3017D01*
G01D02*
G02X24999Y1567568I-1575J3175D01*
G01D02*
X21322D01*
G01D02*
G02X20266Y1568006I1J1494D01*
G01D02*
X20265D01*
G01D02*
G03X18109Y1568899I-2156J-2156D01*
G01D02*
X18103Y1568893D01*
G01X30520Y1572049D02*
G02X29669Y1569455I-7152J910D01*
G01D02*
G02X27499Y1567050I-6301J3504D01*
G01D02*
G02X27129Y1566818I-2498J3573D01*
G01D02*
G02X24999Y1566262I-2130J3804D01*
G01D02*
X21655D01*
G01D02*
G03X21477Y1566251I6J-1550D01*
G01D02*
G03X20666Y1565915I0J-1147D01*
G01D02*
X20559Y1565808D01*
G01D02*
G02X18517Y1564962I-2042J2042D01*
G01D02*
X18511Y1564956D01*
G01X29626Y1645002D02*
G02X30579Y1642701I-2301J-2301D01*
G01X33026Y1645051D02*
G03X31879Y1642282I2769J-2769D01*
G01X28600Y1661039D02*
G02X29699Y1658386I-2653J-2653D01*
G01D02*
Y1652406D01*
G01D02*
G02X28511Y1649538I-4056J0D01*
G01D02*
X27200Y1648227D01*
G01D02*
Y1648225D01*
G01D02*
X27011Y1648037D01*
G01D02*
X26181Y1647207D01*
G01D02*
G02X25465Y1646673I-2184J2181D01*
G01D02*
Y1646674D01*
G01D02*
G02X23999Y1646302I-1469J2714D01*
G01D02*
X21641D01*
G01D02*
G02X20740Y1646675I0J1274D01*
G01D02*
G03X18413Y1647639I-2327J-2327D01*
G01D02*
X18407Y1647633D01*
G01X31999Y1661127D02*
G03X30999Y1658713I2414J-2414D01*
G01D02*
Y1652405D01*
G01D02*
G02X29431Y1648618I-5357J0D01*
G01D02*
X29181Y1648368D01*
G01D02*
Y1648367D01*
G01D02*
X28620Y1647807D01*
G01D02*
X28500Y1647687D01*
G01D02*
Y1647686D01*
G01D02*
X27101Y1646287D01*
G01D02*
G02X23999Y1645002I-3102J3102D01*
G01D02*
X21710D01*
G01D02*
G03X20626Y1644553I0J-1533D01*
G01D02*
G02X18572Y1643702I-2054J2054D01*
G01D02*
X18566Y1643696D01*
G01X29100Y1669500D02*
G02X29549Y1667350I-479J-1222D01*
G01D02*
X25599Y1663400D01*
G01D02*
X25487Y1663285D01*
G01D02*
G02X25228Y1663048I-2979J2996D01*
G01D02*
G02X22500Y1662050I-2727J3227D01*
G01D02*
X21766D01*
G01D02*
G02X20590Y1662537I0J1663D01*
G01D02*
G03X18538Y1663387I-2052J-2052D01*
G01D02*
X18532Y1663381D01*
G01X32494Y1669706D02*
X31703Y1668916D01*
G01D02*
G03X31200Y1667702I1214J-1214D01*
G01D02*
Y1667700D01*
G01D02*
G02X30819Y1666780I-1301J0D01*
G01D02*
X26523Y1662484D01*
G01D02*
X26410Y1662369D01*
G01D02*
G02X22500Y1660751I-3907J3907D01*
G01D02*
Y1660750D01*
G01D02*
X22188D01*
G01D02*
G03X21353Y1660404I0J-1181D01*
G01D02*
G02X19050Y1659450I-2303J2303D01*
G01D02*
X19044Y1659444D01*
G01X85194Y1748848D02*
G02X86889Y1749550I1695J-1695D01*
G01D02*
X89999D01*
G01D02*
G02X92476Y1748524I0J-3503D01*
G01D02*
X96517Y1744483D01*
G01X97436Y1745404D02*
X93396Y1749444D01*
G01D02*
G03X89999Y1750850I-3396J-3398D01*
G01D02*
X87699D01*
G01D02*
G02X87258Y1750892I-1J2325D01*
G01D02*
G02X86056Y1751530I439J2279D01*
G01D02*
X85341Y1752245D01*
G01X115876Y130050D02*
G02X115576Y129328I-1021J1D01*
G01D02*
X115204Y128956D01*
G01D02*
G02X114754Y128656I-980J983D01*
G01D02*
X114622Y128601D01*
G01D02*
G02X114366Y128550I-256J617D01*
G01D02*
X105814D01*
G01D02*
G03X101864Y126915I1J-5590D01*
G01D02*
X98432Y123484D01*
G01X115876Y125973D02*
G03X114234Y127250I-1642J-417D01*
G01D02*
X105815D01*
G01D02*
G03X104362Y126996I1J-4290D01*
G01D02*
G03X102783Y125995I1452J-4037D01*
G01D02*
X99352Y122564D01*
G01X99499Y130650D02*
G03X101299Y134996I-4346J4346D01*
G01D02*
Y177250D01*
G01X98579Y131570D02*
G03X99998Y134996I-3426J3426D01*
G01D02*
X99999Y134995D01*
G01D02*
Y177250D01*
G01X124011Y233599D02*
G03X128112Y231900I4101J4101D01*
G01D02*
X819160D01*
G01X124931Y234518D02*
G03X128113Y233200I3182J3182D01*
G01D02*
X819160D01*
G01X126249Y239100D02*
X126928Y238420D01*
G01D02*
G03X130599Y236900I3670J3671D01*
G01D02*
X816263D01*
G01X125479Y238031D02*
X126008Y237501D01*
G01D02*
G03X130599Y235600I4590J4591D01*
G01D02*
X816263D01*
G01X122799Y249150D02*
X123204Y249555D01*
G01D02*
G02X124399Y250050I1195J-1195D01*
G01D02*
X125499D01*
G01D02*
G03X127799Y252350I0J2300D01*
G01D02*
Y255483D01*
G01D02*
G03X127018Y257367I-2665J-1D01*
G01D02*
X127019Y257368D01*
G01D02*
X118194Y266194D01*
G01X122397Y252688D02*
Y252036D01*
G01D02*
G03X122598Y251551I686J0D01*
G01D02*
G03X123083Y251350I485J485D01*
G01D02*
X125499D01*
G01D02*
G03X126499Y252350I0J1000D01*
G01D02*
Y255505D01*
G01D02*
G03X126114Y256433I-1313J-1D01*
G01D02*
X125998Y256550D01*
G01X149999Y243504D02*
G02X148420Y242850I-1579J1579D01*
G01D02*
X140335D01*
G01D02*
G02X139249Y243300I0J1536D01*
G01D02*
X132649Y249900D01*
G01D02*
G02X132368Y250212I2773J2780D01*
G01D02*
G02X131499Y252676I3057J2463D01*
G01D02*
Y256550D01*
G01D02*
G03X130386Y259237I-3800J0D01*
G01D02*
X130016Y259607D01*
G01D02*
X127961Y261667D01*
G01D02*
X127956D01*
G01X149999Y239729D02*
G03X149489Y240960I-1741J0D01*
G01D02*
X149199Y241250D01*
G01D02*
G03X148475Y241550I-724J-724D01*
G01D02*
X140334D01*
G01D02*
G02X138329Y242380I0J2837D01*
G01D02*
X131729Y248980D01*
G01D02*
G02X131356Y249396I3699J3692D01*
G01D02*
G02X130199Y252675I4069J3280D01*
G01D02*
Y256550D01*
G01D02*
G03X129468Y258315I-2496J0D01*
G01D02*
X129289Y258494D01*
G01D02*
X127421Y260367D01*
G01D02*
X127415D01*
G01D02*
X119554Y268229D01*
G01X176044Y462200D02*
G03X179226Y463518I0J4500D01*
G01X176046Y460900D02*
G03X180147Y462599I0J5800D01*
G01X172225Y466000D02*
G03X178924Y468775I0J9474D01*
G01X172226Y464700D02*
G03X179843Y467855I-1J10774D01*
G01X162266Y441512D02*
G03X163845Y442073I1J2500D01*
G01D02*
X179869Y455363D01*
G01X162266Y440212D02*
G03X164665Y441065I0J3800D01*
G01D02*
Y441064D01*
G01D02*
G03X164671Y441069I-2430J2922D01*
G01D02*
X164675Y441072D01*
G01D02*
X179292Y453194D01*
G01X125168Y649909D02*
X126831Y652663D01*
G01D02*
X126840Y652679D01*
G01D02*
X157779Y703910D01*
G01D02*
X159317Y706457D01*
G01D02*
X161491Y710056D01*
G01D02*
X172846Y728859D01*
G01D02*
X195529Y762265D01*
G01X196628Y761569D02*
X173941Y728157D01*
G01D02*
X163141Y710272D01*
G01D02*
X160430Y705784D01*
G01D02*
X158893Y703238D01*
G01D02*
X127954Y652007D01*
G01D02*
X125902Y648609D01*
G01X147079Y708470D02*
G03X151250Y718540I-10070J10070D01*
G01D02*
X151251Y718539D01*
G01D02*
Y763389D01*
G01X152551Y763390D02*
Y718540D01*
G01D02*
G02X147999Y707550I-15542J0D01*
G01X129261Y711885D02*
G03X129585Y712856I-778J799D01*
G01D02*
G02X129908Y713826I1102J172D01*
G01D02*
X130704Y714622D01*
G01D02*
G02X131674Y714945I798J-778D01*
G01D02*
G03X132645Y715269I172J1102D01*
G01D02*
X146112Y728736D01*
G01D02*
G03X147551Y732210I-3474J3474D01*
G01X148851Y732209D02*
G02X147032Y727817I-6213J1D01*
G01X178200Y813349D02*
X137249Y772398D01*
G01D02*
G03X135714Y768692I3708J-3707D01*
G01D02*
Y746900D01*
G01D02*
G02X134582Y744167I-3865J0D01*
G01D02*
X134581D01*
G01X179119Y812429D02*
X138169Y771479D01*
G01D02*
G03X137014Y768691I2788J-2788D01*
G01D02*
Y746901D01*
G01D02*
G02X135501Y743248I-5165J-1D01*
G01D02*
Y743247D01*
G01X174533Y814916D02*
X133382Y773765D01*
G01D02*
G03X132014Y770462I3305J-3304D01*
G01D02*
Y748849D01*
G01D02*
G02X131460Y747510I-1893J-1D01*
G01D02*
X130499Y746550D01*
G01X131419Y745630D02*
X132380Y746590D01*
G01D02*
G03X133314Y748849I-2260J2257D01*
G01D02*
Y770461D01*
G01D02*
G02X134302Y772846I3373J0D01*
G01D02*
X175453Y813997D01*
G01X119899Y1032800D02*
Y749124D01*
G01D02*
G02X117329Y742919I-8775J0D01*
G01X121199Y1032799D02*
Y749124D01*
G01D02*
G02X118248Y741999I-10075J-1D01*
G01X114499Y747150D02*
G03X116199Y751254I-4104J4104D01*
G01D02*
Y1029999D01*
G01X115419Y746230D02*
G03X117499Y751253I-5025J5023D01*
G01D02*
Y1030000D01*
G01X104849Y928305D02*
Y751790D01*
G01D02*
X104848Y751789D01*
G01D02*
Y746436D01*
G01D02*
G02X102941Y741832I-6511J0D01*
G01X103861Y740912D02*
X103860Y740913D01*
G01D02*
G03X106148Y746437I-5523J5523D01*
G01D02*
Y751250D01*
G01D02*
X106149Y751251D01*
G01D02*
Y914205D01*
G01X98699Y753750D02*
G03X101149Y759665I-5915J5915D01*
G01D02*
Y804662D01*
G01D02*
G03X100692Y805577I-1115J15D01*
G01D02*
G02X100234Y806492I657J901D01*
G01D02*
Y807617D01*
G01D02*
G02X100692Y808532I1115J14D01*
G01D02*
G03X101149Y809447I-658J900D01*
G01D02*
Y902419D01*
G01X99618Y752830D02*
G03X102449Y759665I-6834J6834D01*
G01D02*
Y926132D01*
G01X185434Y810115D02*
X145334Y770015D01*
G01D02*
G03X143684Y766031I3983J-3983D01*
G01D02*
Y744609D01*
G01D02*
G02X141679Y739769I-6845J0D01*
G01X186353Y809195D02*
X146253Y769095D01*
G01D02*
G03X144984Y766031I3064J-3064D01*
G01D02*
Y744608D01*
G01D02*
G02X142599Y738850I-8145J1D01*
G01X138849Y743200D02*
G03X139567Y744933I-1733J1733D01*
G01D02*
Y766750D01*
G01D02*
G02X141499Y771414I6596J0D01*
G01D02*
X182117Y812032D01*
G01X139768Y742280D02*
Y742281D01*
G01D02*
G03X140867Y744932I-2652J2653D01*
G01D02*
Y766866D01*
G01D02*
G02X142336Y770412I5015J0D01*
G01D02*
X183037Y811113D01*
G01X151251Y763389D02*
G02X152718Y766931I5008J1D01*
G01D02*
X192868Y807081D01*
G01X193787Y806161D02*
X153637Y766011D01*
G01D02*
G03X152551Y763390I2622J-2622D01*
G01X147551Y732210D02*
Y764170D01*
G01D02*
G02X149551Y768997I6827J-1D01*
G01D02*
Y768998D01*
G01D02*
X189601Y809048D01*
G01X190521Y808129D02*
X150670Y768278D01*
G01D02*
X150470Y768079D01*
G01D02*
G03X148851Y764169I3910J-3909D01*
G01D02*
Y732209D01*
G01X96100Y757219D02*
Y836499D01*
G01X175999Y1170468D02*
Y818455D01*
G01D02*
G02X174533Y814916I-5005J0D01*
G01X175453Y813997D02*
G03X177299Y818454I-4459J4458D01*
G01D02*
Y1170469D01*
G01X108845Y931657D02*
X108149Y930960D01*
G01D02*
G02X107399Y930650I-749J750D01*
G01D02*
X106983D01*
G01D02*
G03X105579Y930070I-2J-1984D01*
G01D02*
G03X104849Y928305I1766J-1764D01*
G01X106149Y914205D02*
G02X106606Y915120I1115J15D01*
G01D02*
G03X107064Y916035I-657J901D01*
G01D02*
Y917160D01*
G01D02*
G03X106606Y918075I-1115J14D01*
G01D02*
G02X106149Y918990I658J900D01*
G01D02*
Y928305D01*
G01D02*
G02X106499Y929150I1195J0D01*
G01D02*
G02X106982Y929350I483J-483D01*
G01D02*
X107399D01*
G01D02*
G02X108424Y928926I1J-1449D01*
G01D02*
X109099Y928250D01*
G01X101149Y902419D02*
G03X100692Y903334I-1115J15D01*
G01D02*
G02X100234Y904249I657J901D01*
G01D02*
Y905374D01*
G01D02*
G02X100692Y906289I1115J14D01*
G01D02*
G03X101149Y907204I-658J900D01*
G01D02*
Y908329D01*
G01D02*
G03X100692Y909244I-1115J15D01*
G01D02*
G02X100234Y910159I657J901D01*
G01D02*
Y911284D01*
G01D02*
G02X100692Y912199I1115J14D01*
G01D02*
G03X101149Y913114I-658J900D01*
G01D02*
Y914239D01*
G01D02*
G03X100692Y915154I-1115J15D01*
G01D02*
G02X100234Y916069I657J901D01*
G01D02*
Y917194D01*
G01D02*
G02X100692Y918109I1115J14D01*
G01D02*
G03X101149Y919024I-658J900D01*
G01D02*
Y926132D01*
G01D02*
G03X99899Y929150I-4268J0D01*
G01X102449Y926132D02*
G03X100818Y930070I-5568J1D01*
G01X97479Y1061769D02*
G03X100130Y1055371I9050J2D01*
G01D02*
X100129Y1055370D01*
G01D02*
X117919Y1037581D01*
G01D02*
G02X119899Y1032800I-4782J-4781D01*
G01X98779Y1061770D02*
G03X101049Y1056290I7750J0D01*
G01D02*
X101050Y1056291D01*
G01D02*
X101969Y1055371D01*
G01D02*
X101968Y1055370D01*
G01D02*
X116420Y1040920D01*
G01D02*
X118839Y1038501D01*
G01D02*
G02X121199Y1032799I-5703J-5700D01*
G01X116199Y1029999D02*
G03X113440Y1036658I-9416J0D01*
G01D02*
X95687Y1054411D01*
G01X117499Y1030000D02*
G03X114360Y1037578I-10717J0D01*
G01D02*
X96607Y1055331D01*
G01D02*
G02X95079Y1059020I3689J3689D01*
G01D02*
Y1342443D01*
G01X97479Y1329741D02*
Y1061769D01*
G01X98779Y1329741D02*
Y1061770D01*
G01X156399Y1373115D02*
Y1199073D01*
G01D02*
G03X158221Y1194674I6223J1D01*
G01D02*
X178772Y1174123D01*
G01X157699Y1373116D02*
Y1199074D01*
G01D02*
G03X159141Y1195593I4923J0D01*
G01D02*
X179691Y1175043D01*
G01X152699Y1371700D02*
Y1197515D01*
G01D02*
G03X154504Y1193157I6165J1D01*
G01D02*
X175154Y1172507D01*
G01D02*
G02X175999Y1170468I-2037J-2039D01*
G01X177299Y1170469D02*
G03X176074Y1173426I-4182J0D01*
G01D02*
X155424Y1194076D01*
G01D02*
G02X153999Y1197516I3440J3440D01*
G01D02*
Y1371699D01*
G01X163799Y1375878D02*
Y1201694D01*
G01D02*
G03X165305Y1198058I5144J1D01*
G01D02*
X186306Y1177057D01*
G01X165099Y1375878D02*
Y1201695D01*
G01D02*
G03X166225Y1198977I3844J0D01*
G01D02*
X187225Y1177977D01*
G01X183188Y1174941D02*
X162039Y1196090D01*
G01D02*
G02X160099Y1200774I4683J4683D01*
G01D02*
Y1374673D01*
G01X184108Y1175860D02*
X162958Y1197010D01*
G01D02*
G02X161399Y1200774I3764J3764D01*
G01D02*
Y1374674D01*
G01X193739Y1180092D02*
X173289Y1200542D01*
G01D02*
G02X171199Y1205588I5048J5047D01*
G01D02*
Y1384723D01*
G01X172499Y1384722D02*
Y1205589D01*
G01D02*
G03X174209Y1201461I5838J0D01*
G01D02*
X194659Y1181011D01*
G01X189972Y1178625D02*
X169523Y1199074D01*
G01D02*
G02X167499Y1203961I4886J4886D01*
G01D02*
Y1376798D01*
G01X168799D02*
Y1203961D01*
G01D02*
G03X170442Y1199994I5610J0D01*
G01D02*
X190892Y1179544D01*
G01X127120Y1403154D02*
X155861Y1374413D01*
G01D02*
G02X156399Y1373115I-1296J-1298D01*
G01X128040Y1404073D02*
X156781Y1375332D01*
G01D02*
G02X157699Y1373116I-2216J-2216D01*
G01X123045Y1401995D02*
X152245Y1372795D01*
G01D02*
G02X152698Y1371699I-1098J-1095D01*
G01D02*
X152699Y1371700D01*
G01X153999Y1371699D02*
G03X153164Y1373715I-2851J0D01*
G01D02*
X123964Y1402915D01*
G01X112999Y1361550D02*
G02X111309Y1360850I-1690J1690D01*
G01D02*
X101193D01*
G01D02*
G02X99496Y1361553I0J2400D01*
G01D02*
G03X96384Y1362842I-3112J-3112D01*
G01X112440Y1358196D02*
G02X112291Y1358258I0J210D01*
G01D02*
X111702Y1358847D01*
G01D02*
G03X110005Y1359550I-1697J-1697D01*
G01D02*
X101193D01*
G01D02*
G02X98576Y1360633I-1J3700D01*
G01D02*
X98329Y1360880D01*
G01D02*
G03X96745Y1361536I-1584J-1584D01*
G01X109228Y1337090D02*
X108828Y1336691D01*
G01D02*
G02X106799Y1335850I-2030J2029D01*
G01D02*
X103772D01*
G01D02*
G03X100679Y1334569I0J-4374D01*
G01D02*
X98630Y1332520D01*
G01D02*
G03X97479Y1329741I2778J-2778D01*
G01X109228Y1333315D02*
X108838Y1333706D01*
G01D02*
G03X106799Y1334550I-2038J-2039D01*
G01D02*
X103489D01*
G01D02*
G03X101799Y1333850I0J-2390D01*
G01D02*
X99549Y1331600D01*
G01D02*
G03X98779Y1329741I1859J-1859D01*
G01X97229Y1373337D02*
G02X99235Y1374168I2006J-2006D01*
G01D02*
X100984D01*
G01D02*
G03X104200Y1375500I0J4548D01*
G01D02*
G03X104922Y1377243I-1743J1743D01*
G01D02*
Y1379044D01*
G01D02*
G03X103999Y1381050I-3173J-244D01*
G01D02*
G03X100378Y1382550I-3621J-3621D01*
G01D02*
X95999D01*
G01X97000Y1377600D02*
Y1377290D01*
G01D02*
G03X97700Y1375600I2390J0D01*
G01D02*
G03X98019Y1375468I319J319D01*
G01D02*
X100985D01*
G01D02*
G03X103280Y1376420I-2J3247D01*
G01D02*
G03X103622Y1377244I-822J824D01*
G01D02*
Y1378944D01*
G01D02*
X103623D01*
G01D02*
G03X103079Y1380130I-1875J-142D01*
G01D02*
G03X100377Y1381250I-2702J-2700D01*
G01D02*
X95998D01*
G01X135046Y1405696D02*
X163046Y1377696D01*
G01D02*
G02X163798Y1375878I-1820J-1817D01*
G01D02*
X163799D01*
G01X135965Y1406616D02*
X163965Y1378616D01*
G01D02*
G02X165099Y1375878I-2738J-2738D01*
G01X160099Y1374673D02*
G03X159578Y1375930I-1776J0D01*
G01D02*
X130778Y1404730D01*
G01X161399Y1374674D02*
G03X160498Y1376849I-3076J0D01*
G01D02*
X131698Y1405649D01*
G01X171199Y1384723D02*
G02X172466Y1387782I4328J-1D01*
G01D02*
X172966Y1388282D01*
G01D02*
G03X173872Y1390469I-2187J2187D01*
G01D02*
Y1421205D01*
G01X175172Y1433294D02*
Y1390468D01*
G01D02*
G02X173886Y1387363I-4393J1D01*
G01D02*
X173386Y1386863D01*
G01D02*
G03X172499Y1384722I2141J-2141D01*
G01X167499Y1376798D02*
G03X166312Y1379664I-4053J0D01*
G01D02*
X138463Y1407513D01*
G01X139382Y1408433D02*
X167231Y1380584D01*
G01D02*
G02X168799Y1376798I-3785J-3785D01*
G01X102350Y1348154D02*
X101696Y1347500D01*
G01D02*
G02X99000I-1348J1348D01*
G01D02*
G02X98300Y1349190I1690J1690D01*
G01D02*
Y1352500D01*
G01D02*
X98299D01*
G01D02*
G03X97211Y1355129I-3712J3D01*
G01D02*
X97130Y1355208D01*
G01X96216Y1354283D02*
X96294Y1354206D01*
G01D02*
G02X97000Y1352500I-1706J-1705D01*
G01D02*
Y1349190D01*
G01D02*
G03X98080Y1346580I3691J-1D01*
G01D02*
G03X100821Y1345675I2269J2268D01*
G01D02*
G02X101350Y1345500I91J-612D01*
G01D02*
X102350Y1344500D01*
G01X108499Y1684580D02*
Y1467777D01*
G01D02*
G03X110615Y1462668I7227J1D01*
G01D02*
X123716Y1449567D01*
G01D02*
G02X125049Y1446349I-3219J-3218D01*
G01D02*
Y1408154D01*
G01D02*
G03X127120Y1403154I7073J1D01*
G01X109799Y1684580D02*
Y1467778D01*
G01D02*
G03X111535Y1463587I5927J0D01*
G01D02*
X124635Y1450487D01*
G01D02*
G02X126349Y1446349I-4138J-4138D01*
G01D02*
Y1408155D01*
G01D02*
G03X128040Y1404073I5773J0D01*
G01X103999Y1568938D02*
Y1467231D01*
G01D02*
G03X106248Y1461801I7681J1D01*
G01D02*
X119099Y1448950D01*
G01D02*
G02X121349Y1443518I-5433J-5432D01*
G01D02*
Y1406090D01*
G01D02*
G03X123045Y1401995I5790J-1D01*
G01X123964Y1402915D02*
G02X122649Y1406090I3175J3175D01*
G01D02*
Y1443518D01*
G01D02*
G03X120018Y1449870I-8983J0D01*
G01D02*
X107168Y1462720D01*
G01D02*
G02X105299Y1467232I4512J4512D01*
G01D02*
Y1684107D01*
G01X115899Y1647522D02*
Y1471176D01*
G01D02*
G03X118249Y1465502I8026J1D01*
G01D02*
X130100Y1453651D01*
G01D02*
G02X132449Y1447980I-5671J-5671D01*
G01D02*
Y1411966D01*
G01D02*
G03X135046Y1405696I8866J-1D01*
G01X117199Y1647522D02*
Y1471177D01*
G01D02*
G03X119169Y1466421I6726J0D01*
G01D02*
X131019Y1454571D01*
G01D02*
G02X133749Y1447980I-6590J-6591D01*
G01D02*
Y1411966D01*
G01D02*
G03X135965Y1406616I7566J0D01*
G01X130778Y1404730D02*
G02X128749Y1409629I4901J4900D01*
G01D02*
Y1447625D01*
G01D02*
X128748Y1447624D01*
G01D02*
G03X127233Y1451284I-5177J1D01*
G01D02*
X114783Y1463734D01*
G01D02*
G02X112199Y1469973I6238J6238D01*
G01D02*
Y1647667D01*
G01X131698Y1405649D02*
G02X130049Y1409630I3981J3981D01*
G01D02*
Y1447624D01*
G01D02*
G03X128152Y1452204I-6477J0D01*
G01D02*
X115702Y1464654D01*
G01D02*
G02X113499Y1469973I5319J5319D01*
G01D02*
Y1647666D01*
G01X104935Y1440634D02*
X105108D01*
G01D02*
G03X106088Y1441040I0J1386D01*
G01D02*
G03X106507Y1442050I-1010J1011D01*
G01D02*
Y1442550D01*
G01D02*
G02X106750Y1443135I828J-1D01*
G01D02*
X107053Y1443439D01*
G01D02*
G02X107934Y1443641I880J-1816D01*
G01D02*
X108999D01*
G01D02*
G02X109849Y1443289I0J-1202D01*
G01D02*
G02X109999Y1442927I-362J-362D01*
G01D02*
Y1437049D01*
G01D02*
G02X109000Y1436050I-999J0D01*
G01D02*
X104044D01*
G01D02*
G02X100550Y1437497I0J4943D01*
G01D02*
X99911Y1438137D01*
G01D02*
Y1438138D01*
G01X98991Y1437218D02*
X99630Y1436578D01*
G01D02*
G03X104045Y1434750I4414J4415D01*
G01D02*
X109000D01*
G01D02*
G03X111299Y1437049I0J2299D01*
G01D02*
Y1443050D01*
G01D02*
G03X110854Y1444124I-1519J0D01*
G01D02*
X110772Y1444206D01*
G01D02*
G03X108999Y1444940I-1773J-1773D01*
G01D02*
Y1444941D01*
G01D02*
X104999D01*
G01X173872Y1421205D02*
G03X173414Y1422120I-1115J14D01*
G01D02*
G02X172957Y1423035I658J900D01*
G01D02*
Y1424160D01*
G01D02*
G02X173414Y1425075I1115J15D01*
G01D02*
G03X173872Y1425990I-657J901D01*
G01D02*
Y1433250D01*
G01D02*
G03X172748Y1435961I-3834J-1D01*
G01D02*
X143074Y1465635D01*
G01D02*
G03X139498Y1467117I-3576J-3574D01*
G01D02*
X124999D01*
G01D02*
G03X123808Y1465926I0J-1191D01*
G01D02*
Y1465050D01*
G01X124290Y1469241D02*
G03X126279Y1468417I1989J1989D01*
G01D02*
X139499D01*
G01D02*
G02X143994Y1466555I0J-6357D01*
G01D02*
X173699Y1436850D01*
G01D02*
G02X175172Y1433294I-3556J-3556D01*
G01X117390Y1429976D02*
G02X114672Y1428850I-2718J2718D01*
G01D02*
X106499D01*
G01D02*
X106498Y1428849D01*
G01D02*
G02X101376Y1430972I2J7245D01*
G01X117390Y1426201D02*
X116778Y1426813D01*
G01D02*
G03X114999Y1427550I-1779J-1779D01*
G01D02*
X106369D01*
G01D02*
G02X100456Y1430052I130J8545D01*
G01X138463Y1407513D02*
G02X136149Y1413100I5586J5586D01*
G01D02*
Y1446700D01*
G01D02*
X136150Y1446701D01*
G01D02*
Y1451399D01*
G01D02*
X136149Y1451400D01*
G01D02*
Y1454210D01*
G01D02*
G02X137230Y1456820I3690J0D01*
G01D02*
X137829Y1457419D01*
G01D02*
G02X140560Y1458550I2730J-2730D01*
G01D02*
X141450D01*
G01D02*
G03X142900Y1460000I0J1450D01*
G01X142999Y1456373D02*
X142597Y1456775D01*
G01D02*
G03X141450Y1457250I-1147J-1147D01*
G01D02*
X140559D01*
G01D02*
G03X139874Y1457156I2J-2561D01*
G01D02*
G03X138749Y1456499I686J-2467D01*
G01D02*
X138150Y1455900D01*
G01D02*
X138149D01*
G01D02*
G03X137449Y1454210I1690J-1690D01*
G01D02*
Y1451939D01*
G01D02*
X137450Y1451938D01*
G01D02*
Y1446162D01*
G01D02*
X137449Y1446161D01*
G01D02*
Y1413100D01*
G01D02*
G03X139382Y1408433I6600J0D01*
G01X103999Y1684106D02*
Y1579633D01*
G01D02*
G02X103542Y1578718I-1115J-15D01*
G01D02*
G03X103084Y1577803I657J-901D01*
G01D02*
Y1576678D01*
G01D02*
G03X103542Y1575763I1115J-14D01*
G01D02*
G02X103999Y1574848I-658J-900D01*
G01D02*
Y1573723D01*
G01D02*
G02X103542Y1572808I-1115J-15D01*
G01D02*
G03X103084Y1571893I657J-901D01*
G01D02*
Y1570768D01*
G01D02*
G03X103542Y1569853I1115J-14D01*
G01D02*
G02X103999Y1568938I-658J-900D01*
G01X100949Y1737453D02*
Y1695878D01*
G01D02*
G03X102641Y1691793I5779J1D01*
G01D02*
X107541Y1686893D01*
G01D02*
G02X108499Y1684580I-2313J-2313D01*
G01X102249Y1737812D02*
Y1695879D01*
G01D02*
G03X103561Y1692712I4479J0D01*
G01D02*
X108460Y1687813D01*
G01D02*
G02X109799Y1684580I-3232J-3232D01*
G01X96334Y1722854D02*
G03X96792Y1721939I1115J-14D01*
G01D02*
G02X97249Y1721024I-658J-900D01*
G01D02*
Y1719899D01*
G01D02*
G02X96792Y1718984I-1115J-15D01*
G01D02*
G03X96334Y1718069I657J-901D01*
G01D02*
Y1716944D01*
G01D02*
G03X96792Y1716029I1115J-14D01*
G01D02*
G02X97249Y1715114I-658J-900D01*
G01D02*
Y1713989D01*
G01D02*
G02X96792Y1713074I-1115J-15D01*
G01D02*
G03X96334Y1712159I657J-901D01*
G01D02*
Y1711034D01*
G01D02*
G03X96792Y1710119I1115J-14D01*
G01D02*
G02X97249Y1709204I-658J-900D01*
G01D02*
Y1694463D01*
G01D02*
G03X99025Y1690175I6063J-1D01*
G01D02*
X103224Y1685976D01*
G01D02*
G02X103999Y1684106I-1868J-1870D01*
G01X105299Y1684107D02*
G03X104144Y1686895I-3943J0D01*
G01D02*
X99944Y1691095D01*
G01D02*
G02X98549Y1694463I3368J3368D01*
G01D02*
Y1742717D01*
G01X153249Y1756693D02*
Y1693288D01*
G01D02*
G02X149796Y1684952I-11789J0D01*
G01D02*
X118397Y1653553D01*
G01D02*
G03X115899Y1647522I6030J-6030D01*
G01X154549Y1801600D02*
Y1693287D01*
G01D02*
G02X150716Y1684033I-13089J1D01*
G01D02*
X119316Y1652633D01*
G01D02*
G03X117199Y1647522I5111J-5111D01*
G01X112199Y1647667D02*
G02X115679Y1656069I11884J-1D01*
G01D02*
X144279Y1684669D01*
G01D02*
G03X147499Y1692442I-7774J7774D01*
G01D02*
Y1799800D01*
G01X113499Y1647666D02*
G02X116599Y1655150I10584J0D01*
G01D02*
X145198Y1683749D01*
G01D02*
G03X148799Y1692443I-8693J8693D01*
G01D02*
Y1799801D01*
G01X109499Y1743550D02*
X109154Y1743205D01*
G01D02*
G02X105973Y1741850I-3272J3270D01*
G01D02*
G02X105883I-45J4626D01*
G01D02*
G03X102221Y1740524I1J-5722D01*
G01D02*
G03X100949Y1737453I3071J-3071D01*
G01X109399Y1739550D02*
Y1739701D01*
G01D02*
G03X107782Y1740861I-1225J0D01*
G01D02*
G02X105999Y1740550I-1898J5614D01*
G01D02*
X105599D01*
G01D02*
G03X102924Y1739442I0J-3783D01*
G01D02*
G03X102249Y1737812I1630J-1630D01*
G01X96517Y1744483D02*
G02X97249Y1742715I-1768J-1768D01*
G01D02*
Y1737629D01*
G01D02*
G02X96792Y1736714I-1115J-15D01*
G01D02*
G03X96334Y1735799I657J-901D01*
G01D02*
Y1734674D01*
G01D02*
G03X96792Y1733759I1115J-14D01*
G01D02*
G02X97249Y1732844I-658J-900D01*
G01D02*
Y1731719D01*
G01D02*
G02X96792Y1730804I-1115J-15D01*
G01D02*
G03X96334Y1729889I657J-901D01*
G01D02*
Y1728764D01*
G01D02*
G03X96792Y1727849I1115J-14D01*
G01D02*
G02X97249Y1726934I-658J-900D01*
G01D02*
Y1725809D01*
G01D02*
G02X96792Y1724894I-1115J-15D01*
G01D02*
G03X96334Y1723979I657J-901D01*
G01D02*
Y1722854D01*
G01X98549Y1742717D02*
G03X97436Y1745404I-3800J0D01*
G01X149006Y1807692D02*
X151584Y1805115D01*
G01D02*
X151941Y1804759D01*
G01D02*
G02X153250Y1801600I-3160J-3160D01*
G01D02*
X153249D01*
G01D02*
Y1785118D01*
G01D02*
G02X152792Y1784203I-1115J-15D01*
G01D02*
G03X152334Y1783288I657J-901D01*
G01D02*
Y1782163D01*
G01D02*
G03X152792Y1781248I1115J-14D01*
G01D02*
G02X153249Y1780333I-658J-900D01*
G01D02*
Y1779208D01*
G01D02*
G02X152792Y1778293I-1115J-15D01*
G01D02*
G03X152334Y1777378I657J-901D01*
G01D02*
Y1776253D01*
G01D02*
G03X152792Y1775338I1115J-14D01*
G01D02*
G02X153249Y1774423I-658J-900D01*
G01D02*
Y1773298D01*
G01D02*
G02X152792Y1772383I-1115J-15D01*
G01D02*
G03X152334Y1771468I657J-901D01*
G01D02*
Y1770343D01*
G01D02*
G03X152792Y1769428I1115J-14D01*
G01D02*
G02X153249Y1768513I-658J-900D01*
G01D02*
Y1767388D01*
G01D02*
G02X152792Y1766473I-1115J-15D01*
G01D02*
G03X152334Y1765558I657J-901D01*
G01D02*
Y1764433D01*
G01D02*
G03X152792Y1763518I1115J-14D01*
G01D02*
G02X153249Y1762603I-658J-900D01*
G01D02*
Y1761478D01*
G01D02*
G02X152792Y1760563I-1115J-15D01*
G01D02*
G03X152334Y1759648I657J-901D01*
G01D02*
Y1758523D01*
G01D02*
G03X152792Y1757608I1115J-14D01*
G01D02*
G02X153249Y1756693I-658J-900D01*
G01X152860Y1805679D02*
G02X154549Y1801600I-4079J-4078D01*
G01X147499Y1799800D02*
G03X145400Y1804700I-6603J71D01*
G01D02*
G02X133846Y1815855I311665J334374D01*
G01X148799Y1799801D02*
G03X146287Y1805651I-7903J71D01*
G01X123393Y1870859D02*
G02X124734Y1872200I1341J0D01*
G01D02*
X139605D01*
G01D02*
G02X143863Y1870436I0J-6020D01*
G01D02*
X144248Y1870051D01*
G01D02*
Y1870049D01*
G01D02*
X145478Y1868819D01*
G01D02*
G02X147601Y1863700I-5118J-5122D01*
G01D02*
X147600D01*
G01D02*
Y1811090D01*
G01D02*
G03X149007Y1807693I4803J-1D01*
G01D02*
X149006Y1807692D01*
G01X123592Y1874254D02*
G03X125412Y1873500I1820J1820D01*
G01D02*
X139606D01*
G01D02*
G02X144782Y1871356I0J-7320D01*
G01D02*
X146250Y1869888D01*
G01D02*
X146398Y1869739D01*
G01D02*
G02X148900Y1863700I-6039J-6040D01*
G01D02*
Y1811089D01*
G01D02*
G03X149926Y1808612I3503J0D01*
G01D02*
X152503Y1806035D01*
G01D02*
X152860Y1805679D01*
G01X133846Y1815855D02*
G02X131600Y1821278I5422J5422D01*
G01D02*
Y1860420D01*
G01D02*
G02X132502Y1862598I3079J1D01*
G01D02*
X132501Y1862599D01*
G01D02*
X132644Y1862742D01*
G01D02*
G02X135199Y1863800I2555J-2556D01*
G01D02*
X135800D01*
G01D02*
G03X137247Y1864400I-1J2047D01*
G01D02*
X137999Y1865151D01*
G01X146287Y1805651D02*
G02X134766Y1816775I310791J333411D01*
G01D02*
X134765Y1816774D01*
G01D02*
G02X132900Y1821277I4503J4503D01*
G01D02*
Y1860421D01*
G01D02*
G02X133421Y1861679I1779J0D01*
G01D02*
X133564Y1861822D01*
G01D02*
G02X135200Y1862500I1636J-1635D01*
G01D02*
X136300D01*
G01D02*
G02X137488Y1862008I0J-1680D01*
G01D02*
X137999Y1861497D01*
G01X179226Y463518D02*
X181653Y465945D01*
G01D02*
X181654D01*
G01D02*
X777376Y1061667D01*
G01X180147Y462599D02*
X182574Y465026D01*
G01D02*
X778296Y1060747D01*
G01X178924Y468775D02*
X179403Y469254D01*
G01D02*
X179404D01*
G01D02*
X774419Y1064270D01*
G01X179843Y467855D02*
X179942Y467954D01*
G01D02*
X179943D01*
G01D02*
X775339Y1063350D01*
G01X179869Y455363D02*
X180699Y455862D01*
G01D02*
X181439Y456157D01*
G01D02*
X181843Y456317D01*
G01D02*
X181949D01*
G01D02*
X834074Y661025D01*
G01X179292Y453194D02*
X180630Y454302D01*
G01D02*
X181279Y454693D01*
G01D02*
X181877Y454932D01*
G01D02*
X181881D01*
G01D02*
X834463Y659784D01*
G01X817275Y1826081D02*
X192400Y764246D01*
G01X818397Y1825421D02*
X193499Y763550D01*
G01X195529Y762265D02*
X291338Y925070D01*
G01X292455Y924404D02*
X196628Y761569D01*
G01X187399Y814859D02*
G02X185434Y810115I-6709J0D01*
G01X188699Y814859D02*
G02X186353Y809195I-8009J-1D01*
G01X183037Y811113D02*
G03X184999Y815850I-4739J4738D01*
G01X192868Y807081D02*
G03X194799Y811743I-4662J4662D01*
G01D02*
Y1177534D01*
G01X196099Y1177535D02*
Y811743D01*
G01D02*
G02X193787Y806161I-7893J-1D01*
G01X189601Y809048D02*
Y809049D01*
G01D02*
G03X191099Y812662I-3613J3615D01*
G01X192399Y812663D02*
G02X190521Y808129I-6412J0D01*
G01X179699Y1171886D02*
Y816968D01*
G01D02*
G02X178200Y813349I-5118J0D01*
G01X180999Y1171885D02*
Y816968D01*
G01D02*
G02X179119Y812429I-6418J-1D01*
G01X187399Y1174418D02*
Y814859D01*
G01X188699Y1174418D02*
Y814859D01*
G01X182117Y812032D02*
G03X183699Y815851I-3819J3819D01*
G01D02*
Y1173708D01*
G01X184999Y815850D02*
Y1173709D01*
G01X191099Y812662D02*
Y1175905D01*
G01X192399Y1175906D02*
Y812663D01*
G01X178772Y1174123D02*
G02X179698Y1171885I-2240J-2237D01*
G01D02*
X179699Y1171886D01*
G01X179691Y1175043D02*
G02X180999Y1171885I-3158J-3158D01*
G01X186306Y1177057D02*
G02X187398Y1174418I-2641J-2638D01*
G01D02*
X187399D01*
G01X187225Y1177977D02*
G02X188699Y1174418I-3559J-3559D01*
G01X183699Y1173708D02*
G03X183188Y1174941I-1742J0D01*
G01X184999Y1173709D02*
G03X184108Y1175860I-3042J0D01*
G01X194799Y1177534D02*
G03X193739Y1180092I-3616J0D01*
G01X194659Y1181011D02*
G02X196099Y1177535I-3476J-3476D01*
G01X191099Y1175905D02*
G03X189972Y1178625I-3845J0D01*
G01X190892Y1179544D02*
G02X192399Y1175906I-3638J-3638D01*
G01X276099Y433636D02*
G03X280120Y434048I1J19820D01*
G01D02*
G03X282747Y434823I-3365J16247D01*
G01D02*
X798618Y642139D01*
G01X276099Y432336D02*
G03X280296Y432766I-1J20709D01*
G01D02*
G03X280387Y432785I-4050J19624D01*
G01D02*
G03X283100Y433563I-4105J19433D01*
G01D02*
X800299Y641413D01*
G01X291338Y925070D02*
X398202Y1102027D01*
G01X339087Y1001622D02*
X293567Y926245D01*
G01D02*
X292455Y924404D01*
G01X399315Y1101355D02*
X339087Y1001622D01*
G01X404830Y947194D02*
X568807Y1149516D01*
G01X405841Y946376D02*
X569817Y1148697D01*
G01X398202Y1102027D02*
X488787Y1252027D01*
G01X443578Y1174650D02*
X399315Y1101355D01*
G01X489900Y1251355D02*
X443578Y1174650D01*
G01X488787Y1252027D02*
X652983Y1523921D01*
G01X654096Y1523249D02*
X489900Y1251355D01*
G01X568807Y1149516D02*
X817202Y1455998D01*
G01X569817Y1148697D02*
X817499Y1454298D01*
G01X652983Y1523921D02*
X812802Y1788567D01*
G01X813915Y1787895D02*
X654096Y1523249D01*
G01X819160Y231900D02*
G03X824329Y234041I0J7310D01*
G01X819160Y233200D02*
G03X823409Y234960I0J6010D01*
G01D02*
X839176Y250727D01*
G01D02*
G02X841863Y251840I2687J-2687D01*
G01X824329Y234041D02*
X840096Y249808D01*
G01X816263Y236900D02*
G03X820505Y238657I0J5999D01*
G01D02*
X835633Y253783D01*
G01D02*
G02X839875Y255540I4242J-4242D01*
G01D02*
X859118D01*
G01X816263Y235600D02*
G03X821425Y237737I1J7300D01*
G01D02*
X836553Y252863D01*
G01D02*
G02X839875Y254240I3323J-3322D01*
G01D02*
X859116D01*
G01X798618Y642139D02*
X802985Y643920D01*
G01D02*
X802992Y643923D01*
G01D02*
X802993D01*
G01D02*
X836319Y657326D01*
G01X800299Y641413D02*
X803476Y642716D01*
G01D02*
X803477D01*
G01D02*
X836805Y656117D01*
G01X836319Y657326D02*
G02X837737Y657600I1417J-3526D01*
G01D02*
X847629D01*
G01X836805Y656117D02*
X836809Y656119D01*
G01D02*
G02X837742Y656300I934J-2319D01*
G01D02*
X846842D01*
G01X834074Y661025D02*
G02X835871Y661300I1796J-5725D01*
G01D02*
X849603D01*
G01X834463Y659784D02*
G02X835871Y660000I1408J-4484D01*
G01D02*
X849603D01*
G01X777376Y1061667D02*
G02X781299Y1063292I3923J-3923D01*
G01D02*
X847999D01*
G01X778296Y1060747D02*
G02X781299Y1061992I3004J-3002D01*
G01D02*
X846026D01*
G01X774419Y1064270D02*
G02X781489Y1067199I7071J-7071D01*
G01D02*
X867281D01*
G01X775339Y1063350D02*
G02X781490Y1065899I6152J-6150D01*
G01D02*
X867280D01*
G01X845209Y1467526D02*
X834716Y1457033D01*
G01X846135Y1466613D02*
X835635Y1456113D01*
G01D02*
X835640Y1456108D01*
G01X817202Y1455998D02*
X818030Y1457020D01*
G01D02*
X832229Y1471219D01*
G01D02*
G02X835443Y1472550I3213J-3213D01*
G01D02*
X853299D01*
G01X817499Y1454298D02*
X817598Y1454420D01*
G01D02*
X818213Y1455179D01*
G01D02*
X818212Y1455180D01*
G01D02*
X818955Y1456096D01*
G01D02*
X818949Y1456100D01*
G01D02*
X833149Y1470300D01*
G01D02*
G02X835443Y1471250I2294J-2294D01*
G01D02*
X853607D01*
G01X812802Y1788567D02*
X815549Y1793112D01*
G01D02*
X853210Y1855477D01*
G01X854323Y1854804D02*
X816662Y1792440D01*
G01D02*
X813915Y1787895D01*
G01X843620Y1870848D02*
X817275Y1826081D01*
G01X844804Y1870294D02*
X818397Y1825421D01*
G01X841863Y251840D02*
X848580D01*
G01D02*
G02X850000Y251252I0J-2008D01*
G01D02*
X851278Y249974D01*
G01X840096Y249808D02*
G02X841864Y250540I1768J-1768D01*
G01D02*
X846671D01*
G01D02*
G02X847878Y250040I0J-1707D01*
G01X859118Y255540D02*
G02X861218Y254670I0J-2970D01*
G01D02*
X873018Y242870D01*
G01D02*
G03X874273Y242350I1255J1255D01*
G01D02*
X875999D01*
G01D02*
G03X876939Y242740I-1J1330D01*
G01D02*
X878078Y243878D01*
G01X859116Y254240D02*
G02X860299Y253750I0J-1673D01*
G01D02*
X871899Y242150D01*
G01D02*
G03X874555Y241050I2656J2656D01*
G01D02*
X876199D01*
G01D02*
G02X876593Y241015I-1J-2250D01*
G01D02*
G02X877571Y240610I0J-1383D01*
G01D02*
X878078Y240103D01*
G01X877079Y646633D02*
G02X877859Y646310I0J-1103D01*
G01D02*
X878596Y645573D01*
G01X847629Y657600D02*
G02X849976Y656628I0J-3319D01*
G01D02*
X851172Y655432D01*
G01X846842Y656300D02*
G02X847772Y655370I0J-930D01*
G01X849603Y661300D02*
G02X853845Y659543I0J-5999D01*
G01D02*
X864618Y648770D01*
G01D02*
G03X866639Y647933I2021J2021D01*
G01D02*
X876521D01*
G01D02*
G03X877648Y648400I0J1594D01*
G01D02*
X878596Y649348D01*
G01X849603Y660000D02*
G02X852925Y658623I-1J-4699D01*
G01D02*
X863698Y647850D01*
G01D02*
G03X866636Y646633I2938J2938D01*
G01D02*
X877079D01*
G01X870438Y1064205D02*
Y1055550D01*
G01D02*
G03X871102Y1053947I2267J0D01*
G01D02*
X871299Y1053750D01*
G01D02*
G03X872748Y1053150I1449J1449D01*
G01D02*
X874999D01*
G01D02*
G03X877781Y1054303I-1J3935D01*
G01D02*
X877964Y1054485D01*
G01X869138Y1064206D02*
Y1055550D01*
G01D02*
G03X870182Y1053027I3567J-1D01*
G01D02*
X870379Y1052830D01*
G01D02*
G03X872749Y1051850I2367J2369D01*
G01D02*
X875000D01*
G01D02*
G03X876837Y1052183I0J5235D01*
G01D02*
G02X878232Y1051216I362J-967D01*
G01D02*
X878233Y1051095D01*
G01X847999Y1063292D02*
G02X849677Y1062597I0J-2373D01*
G01D02*
X850833Y1061441D01*
G01X846026Y1061992D02*
G02X846291Y1061971I-2J-1707D01*
G01D02*
G02X846962Y1061711I-267J-1685D01*
G01D02*
G02X847233Y1061492I-931J-1430D01*
G01X867281Y1067199D02*
G02X869510Y1066277I-1J-3158D01*
G01D02*
X869627Y1066161D01*
G01D02*
G02X870438Y1064205I-1948J-1954D01*
G01X867280Y1065899D02*
G02X868593Y1065355I-1J-1858D01*
G01D02*
X868710Y1065239D01*
G01D02*
G02X869138Y1064206I-1031J-1032D01*
G01X852288Y1466346D02*
X851521Y1467113D01*
G01D02*
G03X846284Y1468224I-3473J-3473D01*
G01D02*
G03X845209Y1467526I1112J-2890D01*
G01X848888Y1466402D02*
X848686Y1466605D01*
G01D02*
G03X846751Y1467014I-1282J-1282D01*
G01D02*
G03X846135Y1466613I639J-1656D01*
G01X853299Y1472550D02*
G02X858487Y1470401I0J-7337D01*
G01D02*
X869406Y1459482D01*
G01D02*
G03X871174Y1458750I1768J1768D01*
G01D02*
X876612D01*
G01D02*
G03X877853Y1459991I0J1241D01*
G01X853607Y1471250D02*
G02X857349Y1469700I0J-5292D01*
G01D02*
X868486Y1458563D01*
G01D02*
G03X871173Y1457450I2687J2687D01*
G01D02*
X877054D01*
G01D02*
G02X878054Y1456450I0J-1000D01*
G01X853499Y1871036D02*
X852536Y1871999D01*
G01D02*
G03X849999Y1873050I-2537J-2537D01*
G01D02*
X846259D01*
G01D02*
G03X844236Y1871893I1J-2348D01*
G01D02*
X843997Y1871486D01*
G01D02*
X843620Y1870848D01*
G01X850099Y1871056D02*
G03X849603Y1871721I-694J0D01*
G01D02*
G03X849405Y1871750I-199J-665D01*
G01D02*
X846260D01*
G01D02*
G03X845357Y1871233I0J-1048D01*
G01D02*
X844804Y1870294D01*
G01X853210Y1855477D02*
X855434Y1859146D01*
G01D02*
X856088Y1860224D01*
G01D02*
X856092Y1860231D01*
G01D02*
G02X857895Y1862530I10416J-6312D01*
G01D02*
G02X863498Y1864850I5603J-5606D01*
G01D02*
X865067D01*
G01D02*
G03X866914Y1865615I0J2612D01*
G01Y1861840D02*
Y1862634D01*
G01D02*
G03X865999Y1863549I-915J0D01*
G01D02*
X863498D01*
G01D02*
G03X858815Y1861610I0J-6625D01*
G01D02*
G03X857200Y1859550I7715J-7711D01*
G01D02*
X856546Y1858472D01*
G01D02*
X854323Y1854804D01*
M02*
